(kicad_sch
	(version 20250114)
	(generator "eeschema")
	(generator_version "9.0")
	(paper "A3")
	(title_block
		(title "LPDDR4 Test Board")
		(date "2024-02-12")
		(rev "1.1.5")
	)
	(text "Debug UART"
		(exclude_from_sim no)
		(at 95.885 33.655 0)
		(effects
			(font
				(size 2.9972 2.9972)
				(thickness 0.5994)
				(bold yes)
			)
			(justify left bottom)
		)
	)
	(text "SD card"
		(exclude_from_sim no)
		(at 326.39 144.78 0)
		(effects
			(font
				(size 2.9972 2.9972)
				(thickness 0.5994)
				(bold yes)
			)
			(justify left bottom)
		)
	)
	(text "User LEDs"
		(exclude_from_sim no)
		(at 189.865 207.645 0)
		(effects
			(font
				(size 2.9972 2.9972)
				(thickness 0.5994)
				(bold yes)
			)
			(justify left bottom)
		)
	)
	(text "HDMI"
		(exclude_from_sim no)
		(at 318.77 31.115 0)
		(effects
			(font
				(size 2.9972 2.9972)
				(thickness 0.5994)
				(bold yes)
			)
			(justify left bottom)
		)
	)
	(text "User buttons"
		(exclude_from_sim no)
		(at 52.705 207.645 0)
		(effects
			(font
				(size 2.9972 2.9972)
				(thickness 0.5994)
				(bold yes)
			)
			(justify left bottom)
		)
	)
	(junction
		(at 209.55 157.48)
		(diameter 0)
		(color 0 0 0 0)
	)
	(junction
		(at 86.995 45.085)
		(diameter 0)
		(color 0 0 0 0)
	)
	(junction
		(at 298.45 41.91)
		(diameter 0)
		(color 0 0 0 0)
	)
	(junction
		(at 86.995 240.665)
		(diameter 0)
		(color 0 0 0 0)
	)
	(junction
		(at 204.47 130.81)
		(diameter 0)
		(color 0 0 0 0)
	)
	(junction
		(at 61.595 234.315)
		(diameter 0)
		(color 0 0 0 0)
	)
	(junction
		(at 330.835 168.91)
		(diameter 0)
		(color 0 0 0 0)
	)
	(junction
		(at 301.625 186.69)
		(diameter 0)
		(color 0 0 0 0)
	)
	(junction
		(at 307.34 150.495)
		(diameter 0)
		(color 0 0 0 0)
	)
	(junction
		(at 74.295 237.49)
		(diameter 0)
		(color 0 0 0 0)
	)
	(junction
		(at 379.73 82.55)
		(diameter 0)
		(color 0 0 0 0)
	)
	(junction
		(at 313.69 57.15)
		(diameter 0)
		(color 0 0 0 0)
	)
	(junction
		(at 201.93 133.35)
		(diameter 0)
		(color 0 0 0 0)
	)
	(junction
		(at 336.55 166.37)
		(diameter 0)
		(color 0 0 0 0)
	)
	(junction
		(at 316.23 59.69)
		(diameter 0)
		(color 0 0 0 0)
	)
	(junction
		(at 319.405 176.53)
		(diameter 0)
		(color 0 0 0 0)
	)
	(junction
		(at 45.72 45.72)
		(diameter 0)
		(color 0 0 0 0)
	)
	(junction
		(at 65.405 107.315)
		(diameter 0)
		(color 0 0 0 0)
	)
	(junction
		(at 83.185 107.315)
		(diameter 0)
		(color 0 0 0 0)
	)
	(junction
		(at 46.355 104.775)
		(diameter 0)
		(color 0 0 0 0)
	)
	(junction
		(at 48.26 231.14)
		(diameter 0)
		(color 0 0 0 0)
	)
	(junction
		(at 83.185 136.525)
		(diameter 0)
		(color 0 0 0 0)
	)
	(junction
		(at 303.53 46.99)
		(diameter 0)
		(color 0 0 0 0)
	)
	(junction
		(at 204.47 143.51)
		(diameter 0)
		(color 0 0 0 0)
	)
	(junction
		(at 39.37 83.82)
		(diameter 0)
		(color 0 0 0 0)
	)
	(junction
		(at 379.73 92.71)
		(diameter 0)
		(color 0 0 0 0)
	)
	(junction
		(at 307.34 184.15)
		(diameter 0)
		(color 0 0 0 0)
	)
	(junction
		(at 306.07 49.53)
		(diameter 0)
		(color 0 0 0 0)
	)
	(junction
		(at 336.55 189.23)
		(diameter 0)
		(color 0 0 0 0)
	)
	(junction
		(at 301.625 150.495)
		(diameter 0)
		(color 0 0 0 0)
	)
	(junction
		(at 313.69 150.495)
		(diameter 0)
		(color 0 0 0 0)
	)
	(junction
		(at 83.185 133.985)
		(diameter 0)
		(color 0 0 0 0)
	)
	(junction
		(at 46.355 83.82)
		(diameter 0)
		(color 0 0 0 0)
	)
	(junction
		(at 325.12 171.45)
		(diameter 0)
		(color 0 0 0 0)
	)
	(junction
		(at 300.99 44.45)
		(diameter 0)
		(color 0 0 0 0)
	)
	(junction
		(at 311.15 54.61)
		(diameter 0)
		(color 0 0 0 0)
	)
	(junction
		(at 330.835 150.495)
		(diameter 0)
		(color 0 0 0 0)
	)
	(junction
		(at 39.37 104.775)
		(diameter 0)
		(color 0 0 0 0)
	)
	(junction
		(at 38.735 64.135)
		(diameter 0)
		(color 0 0 0 0)
	)
	(junction
		(at 31.75 64.135)
		(diameter 0)
		(color 0 0 0 0)
	)
	(junction
		(at 379.73 87.63)
		(diameter 0)
		(color 0 0 0 0)
	)
	(junction
		(at 325.12 150.495)
		(diameter 0)
		(color 0 0 0 0)
	)
	(junction
		(at 379.73 85.09)
		(diameter 0)
		(color 0 0 0 0)
	)
	(junction
		(at 38.735 45.72)
		(diameter 0)
		(color 0 0 0 0)
	)
	(junction
		(at 86.995 51.435)
		(diameter 0)
		(color 0 0 0 0)
	)
	(junction
		(at 379.73 90.17)
		(diameter 0)
		(color 0 0 0 0)
	)
	(junction
		(at 313.69 181.61)
		(diameter 0)
		(color 0 0 0 0)
	)
	(junction
		(at 308.61 52.07)
		(diameter 0)
		(color 0 0 0 0)
	)
	(junction
		(at 319.405 150.495)
		(diameter 0)
		(color 0 0 0 0)
	)
	(junction
		(at 31.75 45.72)
		(diameter 0)
		(color 0 0 0 0)
	)
	(no_connect
		(at 128.905 114.935)
	)
	(no_connect
		(at 128.905 84.455)
	)
	(no_connect
		(at 128.905 55.245)
	)
	(no_connect
		(at 128.905 103.505)
	)
	(no_connect
		(at 128.905 106.045)
	)
	(no_connect
		(at 128.905 93.345)
	)
	(no_connect
		(at 128.905 95.885)
	)
	(no_connect
		(at 128.905 98.425)
	)
	(no_connect
		(at 128.905 100.965)
	)
	(no_connect
		(at 128.905 76.835)
	)
	(no_connect
		(at 353.06 87.63)
	)
	(no_connect
		(at 128.905 125.095)
	)
	(no_connect
		(at 128.905 122.555)
	)
	(no_connect
		(at 128.905 81.915)
	)
	(no_connect
		(at 128.905 127.635)
	)
	(no_connect
		(at 88.265 89.535)
	)
	(no_connect
		(at 88.265 92.075)
	)
	(no_connect
		(at 128.905 60.325)
	)
	(no_connect
		(at 128.905 117.475)
	)
	(no_connect
		(at 128.905 62.865)
	)
	(no_connect
		(at 88.265 94.615)
	)
	(no_connect
		(at 128.905 135.255)
	)
	(no_connect
		(at 128.905 120.015)
	)
	(no_connect
		(at 128.905 132.715)
	)
	(no_connect
		(at 212.09 138.43)
	)
	(wire
		(pts
			(xy 38.735 71.755) (xy 38.735 70.485)
		)
		(stroke
			(width 0)
			(type default)
		)
	)
	(wire
		(pts
			(xy 193.04 260.35) (xy 195.58 260.35)
		)
		(stroke
			(width 0)
			(type default)
		)
	)
	(wire
		(pts
			(xy 139.065 79.375) (xy 144.145 79.375)
		)
		(stroke
			(width 0)
			(type default)
		)
	)
	(wire
		(pts
			(xy 204.47 157.48) (xy 209.55 157.48)
		)
		(stroke
			(width 0)
			(type default)
		)
	)
	(wire
		(pts
			(xy 336.55 166.37) (xy 336.55 158.75)
		)
		(stroke
			(width 0)
			(type default)
		)
	)
	(wire
		(pts
			(xy 86.995 220.98) (xy 86.995 223.52)
		)
		(stroke
			(width 0)
			(type default)
		)
	)
	(wire
		(pts
			(xy 293.37 46.99) (xy 303.53 46.99)
		)
		(stroke
			(width 0)
			(type default)
		)
	)
	(wire
		(pts
			(xy 85.725 45.085) (xy 86.995 45.085)
		)
		(stroke
			(width 0)
			(type default)
		)
	)
	(wire
		(pts
			(xy 45.72 46.99) (xy 45.72 45.72)
		)
		(stroke
			(width 0)
			(type default)
		)
	)
	(wire
		(pts
			(xy 308.61 52.07) (xy 308.61 80.01)
		)
		(stroke
			(width 0)
			(type default)
		)
	)
	(wire
		(pts
			(xy 379.73 92.71) (xy 379.73 95.25)
		)
		(stroke
			(width 0)
			(type default)
		)
	)
	(wire
		(pts
			(xy 199.39 138.43) (xy 201.93 138.43)
		)
		(stroke
			(width 0)
			(type default)
		)
	)
	(wire
		(pts
			(xy 300.99 44.45) (xy 353.06 44.45)
		)
		(stroke
			(width 0)
			(type default)
		)
	)
	(wire
		(pts
			(xy 319.405 150.495) (xy 325.12 150.495)
		)
		(stroke
			(width 0)
			(type default)
		)
	)
	(wire
		(pts
			(xy 61.595 234.315) (xy 91.44 234.315)
		)
		(stroke
			(width 0)
			(type default)
		)
	)
	(wire
		(pts
			(xy 154.305 240.665) (xy 156.845 240.665)
		)
		(stroke
			(width 0)
			(type default)
		)
	)
	(wire
		(pts
			(xy 259.08 243.205) (xy 259.08 240.665)
		)
		(stroke
			(width 0)
			(type default)
		)
	)
	(wire
		(pts
			(xy 298.45 41.91) (xy 298.45 69.85)
		)
		(stroke
			(width 0)
			(type default)
		)
	)
	(wire
		(pts
			(xy 339.09 186.69) (xy 327.66 186.69)
		)
		(stroke
			(width 0)
			(type default)
		)
	)
	(wire
		(pts
			(xy 297.18 85.09) (xy 313.69 85.09)
		)
		(stroke
			(width 0)
			(type default)
		)
	)
	(wire
		(pts
			(xy 250.19 231.14) (xy 252.73 231.14)
		)
		(stroke
			(width 0)
			(type default)
		)
	)
	(wire
		(pts
			(xy 351.79 92.71) (xy 353.06 92.71)
		)
		(stroke
			(width 0)
			(type default)
		)
	)
	(wire
		(pts
			(xy 144.145 90.805) (xy 139.065 90.805)
		)
		(stroke
			(width 0)
			(type default)
		)
	)
	(wire
		(pts
			(xy 283.21 57.15) (xy 288.29 57.15)
		)
		(stroke
			(width 0)
			(type default)
		)
	)
	(wire
		(pts
			(xy 350.52 49.53) (xy 353.06 49.53)
		)
		(stroke
			(width 0)
			(type default)
		)
	)
	(wire
		(pts
			(xy 297.18 74.93) (xy 303.53 74.93)
		)
		(stroke
			(width 0)
			(type default)
		)
	)
	(wire
		(pts
			(xy 88.265 99.695) (xy 65.405 99.695)
		)
		(stroke
			(width 0)
			(type default)
		)
	)
	(wire
		(pts
			(xy 299.085 186.69) (xy 301.625 186.69)
		)
		(stroke
			(width 0)
			(type default)
		)
	)
	(wire
		(pts
			(xy 234.315 240.665) (xy 227.33 240.665)
		)
		(stroke
			(width 0)
			(type default)
		)
	)
	(wire
		(pts
			(xy 313.69 153.67) (xy 313.69 150.495)
		)
		(stroke
			(width 0)
			(type default)
		)
	)
	(wire
		(pts
			(xy 61.595 228.6) (xy 61.595 234.315)
		)
		(stroke
			(width 0)
			(type default)
		)
	)
	(wire
		(pts
			(xy 46.355 104.775) (xy 53.975 104.775)
		)
		(stroke
			(width 0)
			(type default)
		)
	)
	(wire
		(pts
			(xy 283.21 41.91) (xy 288.29 41.91)
		)
		(stroke
			(width 0)
			(type default)
		)
	)
	(wire
		(pts
			(xy 48.26 255.905) (xy 48.26 259.08)
		)
		(stroke
			(width 0)
			(type default)
		)
	)
	(wire
		(pts
			(xy 363.22 189.23) (xy 363.22 186.69)
		)
		(stroke
			(width 0)
			(type default)
		)
	)
	(wire
		(pts
			(xy 353.06 72.39) (xy 351.79 72.39)
		)
		(stroke
			(width 0)
			(type default)
		)
	)
	(wire
		(pts
			(xy 347.98 49.53) (xy 347.98 52.07)
		)
		(stroke
			(width 0)
			(type default)
		)
	)
	(wire
		(pts
			(xy 38.735 53.34) (xy 38.735 52.07)
		)
		(stroke
			(width 0)
			(type default)
		)
	)
	(wire
		(pts
			(xy 330.835 168.91) (xy 330.835 163.83)
		)
		(stroke
			(width 0)
			(type default)
		)
	)
	(wire
		(pts
			(xy 199.39 143.51) (xy 204.47 143.51)
		)
		(stroke
			(width 0)
			(type default)
		)
	)
	(wire
		(pts
			(xy 325.12 150.495) (xy 330.835 150.495)
		)
		(stroke
			(width 0)
			(type default)
		)
	)
	(wire
		(pts
			(xy 209.55 157.48) (xy 209.55 160.02)
		)
		(stroke
			(width 0)
			(type default)
		)
	)
	(wire
		(pts
			(xy 336.55 189.23) (xy 339.09 189.23)
		)
		(stroke
			(width 0)
			(type default)
		)
	)
	(wire
		(pts
			(xy 330.835 158.75) (xy 330.835 150.495)
		)
		(stroke
			(width 0)
			(type default)
		)
	)
	(wire
		(pts
			(xy 88.265 70.485) (xy 85.725 70.485)
		)
		(stroke
			(width 0)
			(type default)
		)
	)
	(wire
		(pts
			(xy 36.83 83.82) (xy 39.37 83.82)
		)
		(stroke
			(width 0)
			(type default)
		)
	)
	(wire
		(pts
			(xy 336.55 153.67) (xy 336.55 150.495)
		)
		(stroke
			(width 0)
			(type default)
		)
	)
	(wire
		(pts
			(xy 337.82 67.31) (xy 353.06 67.31)
		)
		(stroke
			(width 0)
			(type default)
		)
	)
	(wire
		(pts
			(xy 308.61 52.07) (xy 345.44 52.07)
		)
		(stroke
			(width 0)
			(type default)
		)
	)
	(wire
		(pts
			(xy 83.185 114.935) (xy 83.185 116.205)
		)
		(stroke
			(width 0)
			(type default)
		)
	)
	(wire
		(pts
			(xy 299.085 150.495) (xy 301.625 150.495)
		)
		(stroke
			(width 0)
			(type default)
		)
	)
	(wire
		(pts
			(xy 212.09 143.51) (xy 204.47 143.51)
		)
		(stroke
			(width 0)
			(type default)
		)
	)
	(wire
		(pts
			(xy 209.55 153.67) (xy 209.55 157.48)
		)
		(stroke
			(width 0)
			(type default)
		)
	)
	(wire
		(pts
			(xy 52.705 45.72) (xy 52.705 46.99)
		)
		(stroke
			(width 0)
			(type default)
		)
	)
	(wire
		(pts
			(xy 378.46 82.55) (xy 379.73 82.55)
		)
		(stroke
			(width 0)
			(type default)
		)
	)
	(wire
		(pts
			(xy 297.18 77.47) (xy 306.07 77.47)
		)
		(stroke
			(width 0)
			(type default)
		)
	)
	(wire
		(pts
			(xy 297.18 87.63) (xy 316.23 87.63)
		)
		(stroke
			(width 0)
			(type default)
		)
	)
	(wire
		(pts
			(xy 370.84 182.88) (xy 370.84 185.42)
		)
		(stroke
			(width 0)
			(type default)
		)
	)
	(wire
		(pts
			(xy 209.55 148.59) (xy 209.55 146.05)
		)
		(stroke
			(width 0)
			(type default)
		)
	)
	(wire
		(pts
			(xy 195.58 262.89) (xy 195.58 260.35)
		)
		(stroke
			(width 0)
			(type default)
		)
	)
	(wire
		(pts
			(xy 293.37 54.61) (xy 311.15 54.61)
		)
		(stroke
			(width 0)
			(type default)
		)
	)
	(wire
		(pts
			(xy 39.37 83.82) (xy 46.355 83.82)
		)
		(stroke
			(width 0)
			(type default)
		)
	)
	(wire
		(pts
			(xy 39.37 111.125) (xy 39.37 112.395)
		)
		(stroke
			(width 0)
			(type default)
		)
	)
	(wire
		(pts
			(xy 86.995 60.325) (xy 86.995 51.435)
		)
		(stroke
			(width 0)
			(type default)
		)
	)
	(wire
		(pts
			(xy 83.185 122.555) (xy 83.185 125.095)
		)
		(stroke
			(width 0)
			(type default)
		)
	)
	(wire
		(pts
			(xy 325.12 171.45) (xy 325.12 158.75)
		)
		(stroke
			(width 0)
			(type default)
		)
	)
	(wire
		(pts
			(xy 180.34 260.35) (xy 175.895 260.35)
		)
		(stroke
			(width 0)
			(type default)
		)
	)
	(wire
		(pts
			(xy 283.21 44.45) (xy 288.29 44.45)
		)
		(stroke
			(width 0)
			(type default)
		)
	)
	(wire
		(pts
			(xy 133.985 50.165) (xy 128.905 50.165)
		)
		(stroke
			(width 0)
			(type default)
		)
	)
	(wire
		(pts
			(xy 74.295 255.905) (xy 74.295 259.08)
		)
		(stroke
			(width 0)
			(type default)
		)
	)
	(wire
		(pts
			(xy 61.595 255.905) (xy 61.595 259.08)
		)
		(stroke
			(width 0)
			(type default)
		)
	)
	(wire
		(pts
			(xy 31.75 53.34) (xy 31.75 52.07)
		)
		(stroke
			(width 0)
			(type default)
		)
	)
	(wire
		(pts
			(xy 307.34 150.495) (xy 313.69 150.495)
		)
		(stroke
			(width 0)
			(type default)
		)
	)
	(wire
		(pts
			(xy 83.185 107.315) (xy 83.185 109.855)
		)
		(stroke
			(width 0)
			(type default)
		)
	)
	(wire
		(pts
			(xy 340.36 64.77) (xy 353.06 64.77)
		)
		(stroke
			(width 0)
			(type default)
		)
	)
	(wire
		(pts
			(xy 186.69 231.14) (xy 189.23 231.14)
		)
		(stroke
			(width 0)
			(type default)
		)
	)
	(wire
		(pts
			(xy 38.735 64.135) (xy 38.735 65.405)
		)
		(stroke
			(width 0)
			(type default)
		)
	)
	(wire
		(pts
			(xy 204.47 143.51) (xy 204.47 157.48)
		)
		(stroke
			(width 0)
			(type default)
		)
	)
	(wire
		(pts
			(xy 196.215 243.205) (xy 196.215 240.665)
		)
		(stroke
			(width 0)
			(type default)
		)
	)
	(wire
		(pts
			(xy 61.595 220.98) (xy 61.595 223.52)
		)
		(stroke
			(width 0)
			(type default)
		)
	)
	(wire
		(pts
			(xy 139.065 112.395) (xy 144.145 112.395)
		)
		(stroke
			(width 0)
			(type default)
		)
	)
	(wire
		(pts
			(xy 339.09 176.53) (xy 319.405 176.53)
		)
		(stroke
			(width 0)
			(type default)
		)
	)
	(wire
		(pts
			(xy 39.37 106.045) (xy 39.37 104.775)
		)
		(stroke
			(width 0)
			(type default)
		)
	)
	(wire
		(pts
			(xy 378.46 90.17) (xy 379.73 90.17)
		)
		(stroke
			(width 0)
			(type default)
		)
	)
	(wire
		(pts
			(xy 52.705 53.34) (xy 52.705 52.07)
		)
		(stroke
			(width 0)
			(type default)
		)
	)
	(wire
		(pts
			(xy 193.04 220.98) (xy 195.58 220.98)
		)
		(stroke
			(width 0)
			(type default)
		)
	)
	(wire
		(pts
			(xy 379.73 85.09) (xy 379.73 87.63)
		)
		(stroke
			(width 0)
			(type default)
		)
	)
	(wire
		(pts
			(xy 36.83 104.775) (xy 39.37 104.775)
		)
		(stroke
			(width 0)
			(type default)
		)
	)
	(wire
		(pts
			(xy 133.985 71.755) (xy 128.905 71.755)
		)
		(stroke
			(width 0)
			(type default)
		)
	)
	(wire
		(pts
			(xy 38.735 45.72) (xy 45.72 45.72)
		)
		(stroke
			(width 0)
			(type default)
		)
	)
	(wire
		(pts
			(xy 128.905 57.785) (xy 131.445 57.785)
		)
		(stroke
			(width 0)
			(type default)
		)
	)
	(wire
		(pts
			(xy 86.995 47.625) (xy 86.995 45.085)
		)
		(stroke
			(width 0)
			(type default)
		)
	)
	(wire
		(pts
			(xy 283.21 54.61) (xy 288.29 54.61)
		)
		(stroke
			(width 0)
			(type default)
		)
	)
	(wire
		(pts
			(xy 378.46 92.71) (xy 379.73 92.71)
		)
		(stroke
			(width 0)
			(type default)
		)
	)
	(wire
		(pts
			(xy 379.73 90.17) (xy 379.73 92.71)
		)
		(stroke
			(width 0)
			(type default)
		)
	)
	(wire
		(pts
			(xy 74.295 220.345) (xy 74.295 223.52)
		)
		(stroke
			(width 0)
			(type default)
		)
	)
	(wire
		(pts
			(xy 88.265 47.625) (xy 86.995 47.625)
		)
		(stroke
			(width 0)
			(type default)
		)
	)
	(wire
		(pts
			(xy 339.09 179.07) (xy 336.55 179.07)
		)
		(stroke
			(width 0)
			(type default)
		)
	)
	(wire
		(pts
			(xy 201.93 138.43) (xy 201.93 133.35)
		)
		(stroke
			(width 0)
			(type default)
		)
	)
	(wire
		(pts
			(xy 336.55 189.23) (xy 336.55 191.77)
		)
		(stroke
			(width 0)
			(type default)
		)
	)
	(wire
		(pts
			(xy 379.73 87.63) (xy 379.73 90.17)
		)
		(stroke
			(width 0)
			(type default)
		)
	)
	(wire
		(pts
			(xy 200.66 130.81) (xy 204.47 130.81)
		)
		(stroke
			(width 0)
			(type default)
		)
	)
	(wire
		(pts
			(xy 139.065 69.215) (xy 144.145 69.215)
		)
		(stroke
			(width 0)
			(type default)
		)
	)
	(wire
		(pts
			(xy 170.815 260.35) (xy 163.83 260.35)
		)
		(stroke
			(width 0)
			(type default)
		)
	)
	(wire
		(pts
			(xy 86.995 255.905) (xy 86.995 259.08)
		)
		(stroke
			(width 0)
			(type default)
		)
	)
	(wire
		(pts
			(xy 201.93 133.35) (xy 212.09 133.35)
		)
		(stroke
			(width 0)
			(type default)
		)
	)
	(wire
		(pts
			(xy 217.17 240.665) (xy 219.71 240.665)
		)
		(stroke
			(width 0)
			(type default)
		)
	)
	(wire
		(pts
			(xy 351.79 80.01) (xy 353.06 80.01)
		)
		(stroke
			(width 0)
			(type default)
		)
	)
	(wire
		(pts
			(xy 316.23 59.69) (xy 316.23 87.63)
		)
		(stroke
			(width 0)
			(type default)
		)
	)
	(wire
		(pts
			(xy 133.985 79.375) (xy 128.905 79.375)
		)
		(stroke
			(width 0)
			(type default)
		)
	)
	(wire
		(pts
			(xy 170.815 220.98) (xy 163.83 220.98)
		)
		(stroke
			(width 0)
			(type default)
		)
	)
	(wire
		(pts
			(xy 38.735 64.135) (xy 45.72 64.135)
		)
		(stroke
			(width 0)
			(type default)
		)
	)
	(wire
		(pts
			(xy 313.69 85.09) (xy 313.69 57.15)
		)
		(stroke
			(width 0)
			(type default)
		)
	)
	(wire
		(pts
			(xy 243.84 220.98) (xy 239.395 220.98)
		)
		(stroke
			(width 0)
			(type default)
		)
	)
	(wire
		(pts
			(xy 83.185 136.525) (xy 83.185 139.065)
		)
		(stroke
			(width 0)
			(type default)
		)
	)
	(wire
		(pts
			(xy 133.985 69.215) (xy 128.905 69.215)
		)
		(stroke
			(width 0)
			(type default)
		)
	)
	(wire
		(pts
			(xy 48.26 220.98) (xy 48.26 223.52)
		)
		(stroke
			(width 0)
			(type default)
		)
	)
	(wire
		(pts
			(xy 299.085 168.91) (xy 330.835 168.91)
		)
		(stroke
			(width 0)
			(type default)
		)
	)
	(wire
		(pts
			(xy 297.18 72.39) (xy 300.99 72.39)
		)
		(stroke
			(width 0)
			(type default)
		)
	)
	(wire
		(pts
			(xy 297.18 82.55) (xy 311.15 82.55)
		)
		(stroke
			(width 0)
			(type default)
		)
	)
	(wire
		(pts
			(xy 74.295 116.205) (xy 74.295 112.395)
		)
		(stroke
			(width 0)
			(type default)
		)
	)
	(wire
		(pts
			(xy 378.46 85.09) (xy 379.73 85.09)
		)
		(stroke
			(width 0)
			(type default)
		)
	)
	(wire
		(pts
			(xy 350.52 46.99) (xy 350.52 49.53)
		)
		(stroke
			(width 0)
			(type default)
		)
	)
	(wire
		(pts
			(xy 189.23 267.97) (xy 189.23 270.51)
		)
		(stroke
			(width 0)
			(type default)
		)
	)
	(wire
		(pts
			(xy 256.54 220.98) (xy 259.08 220.98)
		)
		(stroke
			(width 0)
			(type default)
		)
	)
	(wire
		(pts
			(xy 78.105 107.315) (xy 83.185 107.315)
		)
		(stroke
			(width 0)
			(type default)
		)
	)
	(wire
		(pts
			(xy 339.09 181.61) (xy 313.69 181.61)
		)
		(stroke
			(width 0)
			(type default)
		)
	)
	(wire
		(pts
			(xy 293.37 49.53) (xy 306.07 49.53)
		)
		(stroke
			(width 0)
			(type default)
		)
	)
	(wire
		(pts
			(xy 83.185 133.985) (xy 88.265 133.985)
		)
		(stroke
			(width 0)
			(type default)
		)
	)
	(wire
		(pts
			(xy 189.865 248.285) (xy 189.865 250.825)
		)
		(stroke
			(width 0)
			(type default)
		)
	)
	(wire
		(pts
			(xy 299.085 181.61) (xy 313.69 181.61)
		)
		(stroke
			(width 0)
			(type default)
		)
	)
	(wire
		(pts
			(xy 370.84 175.26) (xy 370.84 177.8)
		)
		(stroke
			(width 0)
			(type default)
		)
	)
	(wire
		(pts
			(xy 299.085 176.53) (xy 319.405 176.53)
		)
		(stroke
			(width 0)
			(type default)
		)
	)
	(wire
		(pts
			(xy 61.595 234.315) (xy 61.595 245.745)
		)
		(stroke
			(width 0)
			(type default)
		)
	)
	(wire
		(pts
			(xy 46.355 83.82) (xy 53.975 83.82)
		)
		(stroke
			(width 0)
			(type default)
		)
	)
	(wire
		(pts
			(xy 153.67 220.98) (xy 156.21 220.98)
		)
		(stroke
			(width 0)
			(type default)
		)
	)
	(wire
		(pts
			(xy 347.98 52.07) (xy 353.06 52.07)
		)
		(stroke
			(width 0)
			(type default)
		)
	)
	(wire
		(pts
			(xy 83.185 136.525) (xy 88.265 136.525)
		)
		(stroke
			(width 0)
			(type default)
		)
	)
	(wire
		(pts
			(xy 243.84 240.665) (xy 239.395 240.665)
		)
		(stroke
			(width 0)
			(type default)
		)
	)
	(wire
		(pts
			(xy 75.565 81.915) (xy 79.375 81.915)
		)
		(stroke
			(width 0)
			(type default)
		)
	)
	(wire
		(pts
			(xy 46.355 83.82) (xy 46.355 85.09)
		)
		(stroke
			(width 0)
			(type default)
		)
	)
	(wire
		(pts
			(xy 31.75 64.135) (xy 38.735 64.135)
		)
		(stroke
			(width 0)
			(type default)
		)
	)
	(wire
		(pts
			(xy 29.21 83.82) (xy 31.75 83.82)
		)
		(stroke
			(width 0)
			(type default)
		)
	)
	(wire
		(pts
			(xy 195.58 223.52) (xy 195.58 220.98)
		)
		(stroke
			(width 0)
			(type default)
		)
	)
	(wire
		(pts
			(xy 189.23 228.6) (xy 189.23 231.14)
		)
		(stroke
			(width 0)
			(type default)
		)
	)
	(wire
		(pts
			(xy 65.405 107.315) (xy 65.405 109.855)
		)
		(stroke
			(width 0)
			(type default)
		)
	)
	(wire
		(pts
			(xy 351.79 74.93) (xy 353.06 74.93)
		)
		(stroke
			(width 0)
			(type default)
		)
	)
	(wire
		(pts
			(xy 252.73 248.285) (xy 252.73 250.825)
		)
		(stroke
			(width 0)
			(type default)
		)
	)
	(wire
		(pts
			(xy 86.995 240.665) (xy 91.44 240.665)
		)
		(stroke
			(width 0)
			(type default)
		)
	)
	(wire
		(pts
			(xy 83.185 133.985) (xy 83.185 136.525)
		)
		(stroke
			(width 0)
			(type default)
		)
	)
	(wire
		(pts
			(xy 293.37 52.07) (xy 308.61 52.07)
		)
		(stroke
			(width 0)
			(type default)
		)
	)
	(wire
		(pts
			(xy 186.69 270.51) (xy 189.23 270.51)
		)
		(stroke
			(width 0)
			(type default)
		)
	)
	(wire
		(pts
			(xy 31.75 65.405) (xy 31.75 64.135)
		)
		(stroke
			(width 0)
			(type default)
		)
	)
	(wire
		(pts
			(xy 301.625 186.69) (xy 301.625 158.75)
		)
		(stroke
			(width 0)
			(type default)
		)
	)
	(wire
		(pts
			(xy 283.21 59.69) (xy 288.29 59.69)
		)
		(stroke
			(width 0)
			(type default)
		)
	)
	(wire
		(pts
			(xy 342.9 54.61) (xy 342.9 59.69)
		)
		(stroke
			(width 0)
			(type default)
		)
	)
	(wire
		(pts
			(xy 139.065 45.085) (xy 144.145 45.085)
		)
		(stroke
			(width 0)
			(type default)
		)
	)
	(wire
		(pts
			(xy 339.09 171.45) (xy 325.12 171.45)
		)
		(stroke
			(width 0)
			(type default)
		)
	)
	(wire
		(pts
			(xy 46.355 106.045) (xy 46.355 104.775)
		)
		(stroke
			(width 0)
			(type default)
		)
	)
	(wire
		(pts
			(xy 139.065 109.855) (xy 144.145 109.855)
		)
		(stroke
			(width 0)
			(type default)
		)
	)
	(wire
		(pts
			(xy 31.75 46.99) (xy 31.75 45.72)
		)
		(stroke
			(width 0)
			(type default)
		)
	)
	(wire
		(pts
			(xy 297.18 80.01) (xy 308.61 80.01)
		)
		(stroke
			(width 0)
			(type default)
		)
	)
	(wire
		(pts
			(xy 86.995 240.665) (xy 86.995 245.745)
		)
		(stroke
			(width 0)
			(type default)
		)
	)
	(wire
		(pts
			(xy 378.46 87.63) (xy 379.73 87.63)
		)
		(stroke
			(width 0)
			(type default)
		)
	)
	(wire
		(pts
			(xy 306.07 49.53) (xy 306.07 77.47)
		)
		(stroke
			(width 0)
			(type default)
		)
	)
	(wire
		(pts
			(xy 38.735 46.99) (xy 38.735 45.72)
		)
		(stroke
			(width 0)
			(type default)
		)
	)
	(wire
		(pts
			(xy 313.69 150.495) (xy 319.405 150.495)
		)
		(stroke
			(width 0)
			(type default)
		)
	)
	(wire
		(pts
			(xy 39.37 104.775) (xy 46.355 104.775)
		)
		(stroke
			(width 0)
			(type default)
		)
	)
	(wire
		(pts
			(xy 342.9 59.69) (xy 353.06 59.69)
		)
		(stroke
			(width 0)
			(type default)
		)
	)
	(wire
		(pts
			(xy 86.995 228.6) (xy 86.995 240.665)
		)
		(stroke
			(width 0)
			(type default)
		)
	)
	(wire
		(pts
			(xy 316.23 59.69) (xy 337.82 59.69)
		)
		(stroke
			(width 0)
			(type default)
		)
	)
	(wire
		(pts
			(xy 31.75 71.755) (xy 31.75 70.485)
		)
		(stroke
			(width 0)
			(type default)
		)
	)
	(wire
		(pts
			(xy 46.355 111.125) (xy 46.355 112.395)
		)
		(stroke
			(width 0)
			(type default)
		)
	)
	(wire
		(pts
			(xy 306.07 49.53) (xy 347.98 49.53)
		)
		(stroke
			(width 0)
			(type default)
		)
	)
	(wire
		(pts
			(xy 293.37 44.45) (xy 300.99 44.45)
		)
		(stroke
			(width 0)
			(type default)
		)
	)
	(wire
		(pts
			(xy 133.985 66.675) (xy 128.905 66.675)
		)
		(stroke
			(width 0)
			(type default)
		)
	)
	(wire
		(pts
			(xy 250.19 250.825) (xy 252.73 250.825)
		)
		(stroke
			(width 0)
			(type default)
		)
	)
	(wire
		(pts
			(xy 139.065 52.705) (xy 144.145 52.705)
		)
		(stroke
			(width 0)
			(type default)
		)
	)
	(wire
		(pts
			(xy 187.325 250.825) (xy 189.865 250.825)
		)
		(stroke
			(width 0)
			(type default)
		)
	)
	(wire
		(pts
			(xy 311.15 54.61) (xy 311.15 82.55)
		)
		(stroke
			(width 0)
			(type default)
		)
	)
	(wire
		(pts
			(xy 128.905 90.805) (xy 133.985 90.805)
		)
		(stroke
			(width 0)
			(type default)
		)
	)
	(wire
		(pts
			(xy 339.09 166.37) (xy 336.55 166.37)
		)
		(stroke
			(width 0)
			(type default)
		)
	)
	(wire
		(pts
			(xy 46.355 90.17) (xy 46.355 91.44)
		)
		(stroke
			(width 0)
			(type default)
		)
	)
	(wire
		(pts
			(xy 297.18 69.85) (xy 298.45 69.85)
		)
		(stroke
			(width 0)
			(type default)
		)
	)
	(wire
		(pts
			(xy 298.45 41.91) (xy 353.06 41.91)
		)
		(stroke
			(width 0)
			(type default)
		)
	)
	(wire
		(pts
			(xy 128.905 52.705) (xy 133.985 52.705)
		)
		(stroke
			(width 0)
			(type default)
		)
	)
	(wire
		(pts
			(xy 31.75 45.72) (xy 38.735 45.72)
		)
		(stroke
			(width 0)
			(type default)
		)
	)
	(wire
		(pts
			(xy 339.09 168.91) (xy 330.835 168.91)
		)
		(stroke
			(width 0)
			(type default)
		)
	)
	(wire
		(pts
			(xy 139.065 66.675) (xy 144.145 66.675)
		)
		(stroke
			(width 0)
			(type default)
		)
	)
	(wire
		(pts
			(xy 88.265 51.435) (xy 86.995 51.435)
		)
		(stroke
			(width 0)
			(type default)
		)
	)
	(wire
		(pts
			(xy 293.37 59.69) (xy 316.23 59.69)
		)
		(stroke
			(width 0)
			(type default)
		)
	)
	(wire
		(pts
			(xy 319.405 158.75) (xy 319.405 150.495)
		)
		(stroke
			(width 0)
			(type default)
		)
	)
	(wire
		(pts
			(xy 199.39 140.97) (xy 204.47 140.97)
		)
		(stroke
			(width 0)
			(type default)
		)
	)
	(wire
		(pts
			(xy 293.37 41.91) (xy 298.45 41.91)
		)
		(stroke
			(width 0)
			(type default)
		)
	)
	(wire
		(pts
			(xy 283.21 49.53) (xy 288.29 49.53)
		)
		(stroke
			(width 0)
			(type default)
		)
	)
	(wire
		(pts
			(xy 345.44 52.07) (xy 345.44 57.15)
		)
		(stroke
			(width 0)
			(type default)
		)
	)
	(wire
		(pts
			(xy 378.46 80.01) (xy 379.73 80.01)
		)
		(stroke
			(width 0)
			(type default)
		)
	)
	(wire
		(pts
			(xy 300.99 44.45) (xy 300.99 72.39)
		)
		(stroke
			(width 0)
			(type default)
		)
	)
	(wire
		(pts
			(xy 293.37 57.15) (xy 313.69 57.15)
		)
		(stroke
			(width 0)
			(type default)
		)
	)
	(wire
		(pts
			(xy 74.295 237.49) (xy 91.44 237.49)
		)
		(stroke
			(width 0)
			(type default)
		)
	)
	(wire
		(pts
			(xy 48.26 231.14) (xy 48.26 245.745)
		)
		(stroke
			(width 0)
			(type default)
		)
	)
	(wire
		(pts
			(xy 31.75 64.135) (xy 24.13 64.135)
		)
		(stroke
			(width 0)
			(type default)
		)
	)
	(wire
		(pts
			(xy 83.185 122.555) (xy 88.265 122.555)
		)
		(stroke
			(width 0)
			(type default)
		)
	)
	(wire
		(pts
			(xy 303.53 46.99) (xy 303.53 74.93)
		)
		(stroke
			(width 0)
			(type default)
		)
	)
	(wire
		(pts
			(xy 139.065 47.625) (xy 144.145 47.625)
		)
		(stroke
			(width 0)
			(type default)
		)
	)
	(wire
		(pts
			(xy 75.565 55.245) (xy 88.265 55.245)
		)
		(stroke
			(width 0)
			(type default)
		)
	)
	(wire
		(pts
			(xy 45.72 65.405) (xy 45.72 64.135)
		)
		(stroke
			(width 0)
			(type default)
		)
	)
	(wire
		(pts
			(xy 209.55 146.05) (xy 212.09 146.05)
		)
		(stroke
			(width 0)
			(type default)
		)
	)
	(wire
		(pts
			(xy 212.09 125.73) (xy 200.025 125.73)
		)
		(stroke
			(width 0)
			(type default)
		)
	)
	(wire
		(pts
			(xy 217.17 220.98) (xy 219.71 220.98)
		)
		(stroke
			(width 0)
			(type default)
		)
	)
	(wire
		(pts
			(xy 86.995 45.085) (xy 88.265 45.085)
		)
		(stroke
			(width 0)
			(type default)
		)
	)
	(wire
		(pts
			(xy 336.55 179.07) (xy 336.55 189.23)
		)
		(stroke
			(width 0)
			(type default)
		)
	)
	(wire
		(pts
			(xy 200.66 133.35) (xy 201.93 133.35)
		)
		(stroke
			(width 0)
			(type default)
		)
	)
	(wire
		(pts
			(xy 133.985 45.085) (xy 128.905 45.085)
		)
		(stroke
			(width 0)
			(type default)
		)
	)
	(wire
		(pts
			(xy 340.36 57.15) (xy 340.36 64.77)
		)
		(stroke
			(width 0)
			(type default)
		)
	)
	(wire
		(pts
			(xy 83.185 104.775) (xy 83.185 107.315)
		)
		(stroke
			(width 0)
			(type default)
		)
	)
	(wire
		(pts
			(xy 319.405 176.53) (xy 319.405 163.83)
		)
		(stroke
			(width 0)
			(type default)
		)
	)
	(wire
		(pts
			(xy 322.58 186.69) (xy 301.625 186.69)
		)
		(stroke
			(width 0)
			(type default)
		)
	)
	(wire
		(pts
			(xy 307.34 184.15) (xy 307.34 163.83)
		)
		(stroke
			(width 0)
			(type default)
		)
	)
	(wire
		(pts
			(xy 363.22 186.69) (xy 360.68 186.69)
		)
		(stroke
			(width 0)
			(type default)
		)
	)
	(wire
		(pts
			(xy 313.69 181.61) (xy 313.69 158.75)
		)
		(stroke
			(width 0)
			(type default)
		)
	)
	(wire
		(pts
			(xy 65.405 99.695) (xy 65.405 107.315)
		)
		(stroke
			(width 0)
			(type default)
		)
	)
	(wire
		(pts
			(xy 128.905 47.625) (xy 133.985 47.625)
		)
		(stroke
			(width 0)
			(type default)
		)
	)
	(wire
		(pts
			(xy 337.82 59.69) (xy 337.82 67.31)
		)
		(stroke
			(width 0)
			(type default)
		)
	)
	(wire
		(pts
			(xy 65.405 114.935) (xy 65.405 116.205)
		)
		(stroke
			(width 0)
			(type default)
		)
	)
	(wire
		(pts
			(xy 204.47 130.81) (xy 212.09 130.81)
		)
		(stroke
			(width 0)
			(type default)
		)
	)
	(wire
		(pts
			(xy 301.625 150.495) (xy 301.625 153.67)
		)
		(stroke
			(width 0)
			(type default)
		)
	)
	(wire
		(pts
			(xy 29.21 104.775) (xy 31.75 104.775)
		)
		(stroke
			(width 0)
			(type default)
		)
	)
	(wire
		(pts
			(xy 325.12 153.67) (xy 325.12 150.495)
		)
		(stroke
			(width 0)
			(type default)
		)
	)
	(wire
		(pts
			(xy 84.455 81.915) (xy 88.265 81.915)
		)
		(stroke
			(width 0)
			(type default)
		)
	)
	(wire
		(pts
			(xy 139.065 71.755) (xy 144.145 71.755)
		)
		(stroke
			(width 0)
			(type default)
		)
	)
	(wire
		(pts
			(xy 88.265 60.325) (xy 86.995 60.325)
		)
		(stroke
			(width 0)
			(type default)
		)
	)
	(wire
		(pts
			(xy 311.15 54.61) (xy 342.9 54.61)
		)
		(stroke
			(width 0)
			(type default)
		)
	)
	(wire
		(pts
			(xy 139.065 88.265) (xy 144.145 88.265)
		)
		(stroke
			(width 0)
			(type default)
		)
	)
	(wire
		(pts
			(xy 139.065 50.165) (xy 144.145 50.165)
		)
		(stroke
			(width 0)
			(type default)
		)
	)
	(wire
		(pts
			(xy 299.085 166.37) (xy 336.55 166.37)
		)
		(stroke
			(width 0)
			(type default)
		)
	)
	(wire
		(pts
			(xy 353.06 85.09) (xy 351.79 85.09)
		)
		(stroke
			(width 0)
			(type default)
		)
	)
	(wire
		(pts
			(xy 45.72 45.72) (xy 52.705 45.72)
		)
		(stroke
			(width 0)
			(type default)
		)
	)
	(wire
		(pts
			(xy 39.37 85.09) (xy 39.37 83.82)
		)
		(stroke
			(width 0)
			(type default)
		)
	)
	(wire
		(pts
			(xy 39.37 90.17) (xy 39.37 91.44)
		)
		(stroke
			(width 0)
			(type default)
		)
	)
	(wire
		(pts
			(xy 83.185 130.175) (xy 83.185 133.985)
		)
		(stroke
			(width 0)
			(type default)
		)
	)
	(wire
		(pts
			(xy 234.315 220.98) (xy 227.33 220.98)
		)
		(stroke
			(width 0)
			(type default)
		)
	)
	(wire
		(pts
			(xy 379.73 82.55) (xy 379.73 85.09)
		)
		(stroke
			(width 0)
			(type default)
		)
	)
	(wire
		(pts
			(xy 379.73 80.01) (xy 379.73 82.55)
		)
		(stroke
			(width 0)
			(type default)
		)
	)
	(wire
		(pts
			(xy 259.08 223.52) (xy 259.08 220.98)
		)
		(stroke
			(width 0)
			(type default)
		)
	)
	(wire
		(pts
			(xy 279.4 87.63) (xy 279.4 88.9)
		)
		(stroke
			(width 0)
			(type default)
		)
	)
	(wire
		(pts
			(xy 75.565 57.785) (xy 88.265 57.785)
		)
		(stroke
			(width 0)
			(type default)
		)
	)
	(wire
		(pts
			(xy 307.34 158.75) (xy 307.34 150.495)
		)
		(stroke
			(width 0)
			(type default)
		)
	)
	(wire
		(pts
			(xy 330.835 150.495) (xy 336.55 150.495)
		)
		(stroke
			(width 0)
			(type default)
		)
	)
	(wire
		(pts
			(xy 299.085 184.15) (xy 307.34 184.15)
		)
		(stroke
			(width 0)
			(type default)
		)
	)
	(wire
		(pts
			(xy 193.675 240.665) (xy 196.215 240.665)
		)
		(stroke
			(width 0)
			(type default)
		)
	)
	(wire
		(pts
			(xy 204.47 140.97) (xy 204.47 130.81)
		)
		(stroke
			(width 0)
			(type default)
		)
	)
	(wire
		(pts
			(xy 171.45 240.665) (xy 164.465 240.665)
		)
		(stroke
			(width 0)
			(type default)
		)
	)
	(wire
		(pts
			(xy 48.26 231.14) (xy 91.44 231.14)
		)
		(stroke
			(width 0)
			(type default)
		)
	)
	(wire
		(pts
			(xy 70.485 107.315) (xy 65.405 107.315)
		)
		(stroke
			(width 0)
			(type default)
		)
	)
	(wire
		(pts
			(xy 339.09 184.15) (xy 307.34 184.15)
		)
		(stroke
			(width 0)
			(type default)
		)
	)
	(wire
		(pts
			(xy 45.72 71.755) (xy 45.72 70.485)
		)
		(stroke
			(width 0)
			(type default)
		)
	)
	(wire
		(pts
			(xy 88.265 104.775) (xy 83.185 104.775)
		)
		(stroke
			(width 0)
			(type default)
		)
	)
	(wire
		(pts
			(xy 139.065 74.295) (xy 144.145 74.295)
		)
		(stroke
			(width 0)
			(type default)
		)
	)
	(wire
		(pts
			(xy 280.67 87.63) (xy 279.4 87.63)
		)
		(stroke
			(width 0)
			(type default)
		)
	)
	(wire
		(pts
			(xy 283.21 52.07) (xy 288.29 52.07)
		)
		(stroke
			(width 0)
			(type default)
		)
	)
	(wire
		(pts
			(xy 88.265 67.945) (xy 85.725 67.945)
		)
		(stroke
			(width 0)
			(type default)
		)
	)
	(wire
		(pts
			(xy 278.765 69.85) (xy 280.67 69.85)
		)
		(stroke
			(width 0)
			(type default)
		)
	)
	(wire
		(pts
			(xy 153.67 260.35) (xy 156.21 260.35)
		)
		(stroke
			(width 0)
			(type default)
		)
	)
	(wire
		(pts
			(xy 299.085 171.45) (xy 325.12 171.45)
		)
		(stroke
			(width 0)
			(type default)
		)
	)
	(wire
		(pts
			(xy 180.975 240.665) (xy 176.53 240.665)
		)
		(stroke
			(width 0)
			(type default)
		)
	)
	(wire
		(pts
			(xy 303.53 46.99) (xy 350.52 46.99)
		)
		(stroke
			(width 0)
			(type default)
		)
	)
	(wire
		(pts
			(xy 180.34 220.98) (xy 175.895 220.98)
		)
		(stroke
			(width 0)
			(type default)
		)
	)
	(wire
		(pts
			(xy 74.295 237.49) (xy 74.295 245.745)
		)
		(stroke
			(width 0)
			(type default)
		)
	)
	(wire
		(pts
			(xy 301.625 150.495) (xy 307.34 150.495)
		)
		(stroke
			(width 0)
			(type default)
		)
	)
	(wire
		(pts
			(xy 45.72 53.34) (xy 45.72 52.07)
		)
		(stroke
			(width 0)
			(type default)
		)
	)
	(wire
		(pts
			(xy 128.905 109.855) (xy 133.985 109.855)
		)
		(stroke
			(width 0)
			(type default)
		)
	)
	(wire
		(pts
			(xy 256.54 240.665) (xy 259.08 240.665)
		)
		(stroke
			(width 0)
			(type default)
		)
	)
	(wire
		(pts
			(xy 133.985 74.295) (xy 128.905 74.295)
		)
		(stroke
			(width 0)
			(type default)
		)
	)
	(wire
		(pts
			(xy 128.905 112.395) (xy 133.985 112.395)
		)
		(stroke
			(width 0)
			(type default)
		)
	)
	(wire
		(pts
			(xy 48.26 228.6) (xy 48.26 231.14)
		)
		(stroke
			(width 0)
			(type default)
		)
	)
	(wire
		(pts
			(xy 282.575 46.99) (xy 288.29 46.99)
		)
		(stroke
			(width 0)
			(type default)
		)
	)
	(wire
		(pts
			(xy 345.44 57.15) (xy 353.06 57.15)
		)
		(stroke
			(width 0)
			(type default)
		)
	)
	(wire
		(pts
			(xy 31.75 45.72) (xy 29.21 45.72)
		)
		(stroke
			(width 0)
			(type default)
		)
	)
	(wire
		(pts
			(xy 252.73 228.6) (xy 252.73 231.14)
		)
		(stroke
			(width 0)
			(type default)
		)
	)
	(wire
		(pts
			(xy 74.295 228.6) (xy 74.295 237.49)
		)
		(stroke
			(width 0)
			(type default)
		)
	)
	(wire
		(pts
			(xy 128.905 88.265) (xy 133.985 88.265)
		)
		(stroke
			(width 0)
			(type default)
		)
	)
	(wire
		(pts
			(xy 313.69 57.15) (xy 340.36 57.15)
		)
		(stroke
			(width 0)
			(type default)
		)
	)
	(wire
		(pts
			(xy 86.995 51.435) (xy 75.565 51.435)
		)
		(stroke
			(width 0)
			(type default)
		)
	)
	(label "1V8_FT"
		(at 24.13 64.135 0)
		(effects
			(font
				(size 1.27 1.27)
			)
			(justify left bottom)
		)
	)
	(label "VPHY"
		(at 53.975 104.775 180)
		(effects
			(font
				(size 1.27 1.27)
			)
			(justify right bottom)
		)
	)
	(label "C_TMDS_CLK_N"
		(at 318.77 59.69 0)
		(effects
			(font
				(size 1.27 1.27)
			)
			(justify left bottom)
		)
	)
	(label "C_TMDS_D1_N"
		(at 318.77 49.53 0)
		(effects
			(font
				(size 1.27 1.27)
			)
			(justify left bottom)
		)
	)
	(label "C_TMDS_D2_P"
		(at 318.77 41.91 0)
		(effects
			(font
				(size 1.27 1.27)
			)
			(justify left bottom)
		)
	)
	(label "C_TMDS_CLK_P"
		(at 318.77 57.15 0)
		(effects
			(font
				(size 1.27 1.27)
			)
			(justify left bottom)
		)
	)
	(label "C_TMDS_D2_N"
		(at 318.77 44.45 0)
		(effects
			(font
				(size 1.27 1.27)
			)
			(justify left bottom)
		)
	)
	(label "C_TMDS_D0_N"
		(at 318.77 54.61 0)
		(effects
			(font
				(size 1.27 1.27)
			)
			(justify left bottom)
		)
	)
	(label "C_TMDS_D1_P"
		(at 318.77 46.99 0)
		(effects
			(font
				(size 1.27 1.27)
			)
			(justify left bottom)
		)
	)
	(label "1V8_FT"
		(at 75.565 51.435 0)
		(effects
			(font
				(size 1.27 1.27)
			)
			(justify left bottom)
		)
	)
	(label "VPLL"
		(at 75.565 57.785 0)
		(effects
			(font
				(size 1.27 1.27)
			)
			(justify left bottom)
		)
	)
	(label "VPLL"
		(at 53.975 83.82 180)
		(effects
			(font
				(size 1.27 1.27)
			)
			(justify right bottom)
		)
	)
	(label "VPHY"
		(at 75.565 55.245 0)
		(effects
			(font
				(size 1.27 1.27)
			)
			(justify left bottom)
		)
	)
	(label "C_TMDS_D0_P"
		(at 318.77 52.07 0)
		(effects
			(font
				(size 1.27 1.27)
			)
			(justify left bottom)
		)
	)
	(global_label "SD_DAT1"
		(shape input)
		(at 299.085 184.15 180)
		(fields_autoplaced yes)
		(effects
			(font
				(size 1.27 1.27)
			)
			(justify right)
		)
		(property "Intersheetrefs" "${INTERSHEET_REFS}"
			(at 16.51 -10.795 0)
			(effects
				(font
					(size 1.27 1.27)
				)
				(hide yes)
			)
		)
	)
	(global_label "AUX_JTAG_TDI"
		(shape input)
		(at 144.145 69.215 0)
		(fields_autoplaced yes)
		(effects
			(font
				(size 1.27 1.27)
			)
			(justify left)
		)
		(property "Intersheetrefs" "${INTERSHEET_REFS}"
			(at -13.97 -31.115 0)
			(effects
				(font
					(size 1.27 1.27)
				)
				(hide yes)
			)
		)
	)
	(global_label "3V3_SYS"
		(shape input)
		(at 217.17 240.665 180)
		(fields_autoplaced yes)
		(effects
			(font
				(size 1.27 1.27)
			)
			(justify right)
		)
		(property "Intersheetrefs" "${INTERSHEET_REFS}"
			(at -23.495 -3.175 0)
			(effects
				(font
					(size 1.27 1.27)
				)
				(hide yes)
			)
		)
	)
	(global_label "TCK_JTAG"
		(shape input)
		(at 144.145 45.085 0)
		(fields_autoplaced yes)
		(effects
			(font
				(size 1.27 1.27)
			)
			(justify left)
		)
		(property "Intersheetrefs" "${INTERSHEET_REFS}"
			(at -13.97 -31.115 0)
			(effects
				(font
					(size 1.27 1.27)
				)
				(hide yes)
			)
		)
	)
	(global_label "USR_BTN3"
		(shape input)
		(at 91.44 237.49 0)
		(fields_autoplaced yes)
		(effects
			(font
				(size 1.27 1.27)
			)
			(justify left)
		)
		(property "Intersheetrefs" "${INTERSHEET_REFS}"
			(at -49.53 -10.795 0)
			(effects
				(font
					(size 1.27 1.27)
				)
				(hide yes)
			)
		)
	)
	(global_label "TMDS_D1_P"
		(shape input)
		(at 282.575 46.99 180)
		(fields_autoplaced yes)
		(effects
			(font
				(size 1.27 1.27)
			)
			(justify right)
		)
		(property "Intersheetrefs" "${INTERSHEET_REFS}"
			(at 227.33 -333.375 90)
			(effects
				(font
					(size 1.27 1.27)
				)
				(justify left)
				(hide yes)
			)
		)
	)
	(global_label "AUX_JTAG_TDO"
		(shape input)
		(at 144.145 71.755 0)
		(fields_autoplaced yes)
		(effects
			(font
				(size 1.27 1.27)
			)
			(justify left)
		)
		(property "Intersheetrefs" "${INTERSHEET_REFS}"
			(at -13.97 -31.115 0)
			(effects
				(font
					(size 1.27 1.27)
				)
				(hide yes)
			)
		)
	)
	(global_label "UART0_RX"
		(shape input)
		(at 144.145 88.265 0)
		(fields_autoplaced yes)
		(effects
			(font
				(size 1.27 1.27)
			)
			(justify left)
		)
		(property "Intersheetrefs" "${INTERSHEET_REFS}"
			(at -13.97 -31.115 0)
			(effects
				(font
					(size 1.27 1.27)
				)
				(hide yes)
			)
		)
	)
	(global_label "SD_CD"
		(shape input)
		(at 299.085 186.69 180)
		(fields_autoplaced yes)
		(effects
			(font
				(size 1.27 1.27)
			)
			(justify right)
		)
		(property "Intersheetrefs" "${INTERSHEET_REFS}"
			(at 16.51 -10.795 0)
			(effects
				(font
					(size 1.27 1.27)
				)
				(hide yes)
			)
		)
	)
	(global_label "TMDS_D2_N"
		(shape input)
		(at 283.21 44.45 180)
		(fields_autoplaced yes)
		(effects
			(font
				(size 1.27 1.27)
			)
			(justify right)
		)
		(property "Intersheetrefs" "${INTERSHEET_REFS}"
			(at 227.33 -342.9 90)
			(effects
				(font
					(size 1.27 1.27)
				)
				(justify left)
				(hide yes)
			)
		)
	)
	(global_label "UART0_TX"
		(shape input)
		(at 144.145 90.805 0)
		(fields_autoplaced yes)
		(effects
			(font
				(size 1.27 1.27)
			)
			(justify left)
		)
		(property "Intersheetrefs" "${INTERSHEET_REFS}"
			(at -13.97 -31.115 0)
			(effects
				(font
					(size 1.27 1.27)
				)
				(hide yes)
			)
		)
	)
	(global_label "SD_CLK"
		(shape input)
		(at 299.085 176.53 180)
		(fields_autoplaced yes)
		(effects
			(font
				(size 1.27 1.27)
			)
			(justify right)
		)
		(property "Intersheetrefs" "${INTERSHEET_REFS}"
			(at 16.51 -10.795 0)
			(effects
				(font
					(size 1.27 1.27)
				)
				(hide yes)
			)
		)
	)
	(global_label "3V3_SYS"
		(shape input)
		(at 153.67 220.98 180)
		(fields_autoplaced yes)
		(effects
			(font
				(size 1.27 1.27)
			)
			(justify right)
		)
		(property "Intersheetrefs" "${INTERSHEET_REFS}"
			(at -31.75 -3.175 0)
			(effects
				(font
					(size 1.27 1.27)
				)
				(hide yes)
			)
		)
	)
	(global_label "3V3_SYS"
		(shape input)
		(at 29.21 83.82 180)
		(fields_autoplaced yes)
		(effects
			(font
				(size 1.27 1.27)
			)
			(justify right)
		)
		(property "Intersheetrefs" "${INTERSHEET_REFS}"
			(at -73.66 116.84 0)
			(effects
				(font
					(size 1.27 1.27)
				)
				(hide yes)
			)
		)
	)
	(global_label "USR_BTN1"
		(shape input)
		(at 91.44 231.14 0)
		(fields_autoplaced yes)
		(effects
			(font
				(size 1.27 1.27)
			)
			(justify left)
		)
		(property "Intersheetrefs" "${INTERSHEET_REFS}"
			(at -49.53 -10.795 0)
			(effects
				(font
					(size 1.27 1.27)
				)
				(hide yes)
			)
		)
	)
	(global_label "3V3_SYS"
		(shape input)
		(at 86.995 220.98 90)
		(fields_autoplaced yes)
		(effects
			(font
				(size 1.27 1.27)
			)
			(justify left)
		)
		(property "Intersheetrefs" "${INTERSHEET_REFS}"
			(at -49.53 -10.795 0)
			(effects
				(font
					(size 1.27 1.27)
				)
				(hide yes)
			)
		)
	)
	(global_label "USR_LED4"
		(shape input)
		(at 250.19 231.14 180)
		(fields_autoplaced yes)
		(effects
			(font
				(size 1.27 1.27)
			)
			(justify right)
		)
		(property "Intersheetrefs" "${INTERSHEET_REFS}"
			(at 6.985 -0.635 0)
			(effects
				(font
					(size 1.27 1.27)
				)
				(hide yes)
			)
		)
	)
	(global_label "3V3_SYS"
		(shape input)
		(at 29.21 104.775 180)
		(fields_autoplaced yes)
		(effects
			(font
				(size 1.27 1.27)
			)
			(justify right)
		)
		(property "Intersheetrefs" "${INTERSHEET_REFS}"
			(at -73.66 137.795 0)
			(effects
				(font
					(size 1.27 1.27)
				)
				(hide yes)
			)
		)
	)
	(global_label "3V3_SYS"
		(shape input)
		(at 85.725 45.085 180)
		(fields_autoplaced yes)
		(effects
			(font
				(size 1.27 1.27)
			)
			(justify right)
		)
		(property "Intersheetrefs" "${INTERSHEET_REFS}"
			(at 15.875 132.715 0)
			(effects
				(font
					(size 1.27 1.27)
				)
				(hide yes)
			)
		)
	)
	(global_label "TMDS_CLK_P"
		(shape input)
		(at 283.21 57.15 180)
		(fields_autoplaced yes)
		(effects
			(font
				(size 1.27 1.27)
			)
			(justify right)
		)
		(property "Intersheetrefs" "${INTERSHEET_REFS}"
			(at 227.33 -295.275 90)
			(effects
				(font
					(size 1.27 1.27)
				)
				(justify left)
				(hide yes)
			)
		)
	)
	(global_label "TMDS_D0_P"
		(shape input)
		(at 283.21 52.07 180)
		(fields_autoplaced yes)
		(effects
			(font
				(size 1.27 1.27)
			)
			(justify right)
		)
		(property "Intersheetrefs" "${INTERSHEET_REFS}"
			(at 227.33 -314.325 90)
			(effects
				(font
					(size 1.27 1.27)
				)
				(justify left)
				(hide yes)
			)
		)
	)
	(global_label "3V3_SYS"
		(shape input)
		(at 217.17 220.98 180)
		(fields_autoplaced yes)
		(effects
			(font
				(size 1.27 1.27)
			)
			(justify right)
		)
		(property "Intersheetrefs" "${INTERSHEET_REFS}"
			(at -23.495 -3.175 0)
			(effects
				(font
					(size 1.27 1.27)
				)
				(hide yes)
			)
		)
	)
	(global_label "TMS_JTAG"
		(shape input)
		(at 144.145 52.705 0)
		(fields_autoplaced yes)
		(effects
			(font
				(size 1.27 1.27)
			)
			(justify left)
		)
		(property "Intersheetrefs" "${INTERSHEET_REFS}"
			(at -13.97 -31.115 0)
			(effects
				(font
					(size 1.27 1.27)
				)
				(hide yes)
			)
		)
	)
	(global_label "AUX_JTAG_RST"
		(shape input)
		(at 144.145 79.375 0)
		(fields_autoplaced yes)
		(effects
			(font
				(size 1.27 1.27)
			)
			(justify left)
		)
		(property "Intersheetrefs" "${INTERSHEET_REFS}"
			(at -13.97 -31.115 0)
			(effects
				(font
					(size 1.27 1.27)
				)
				(hide yes)
			)
		)
	)
	(global_label "3V3_SYS"
		(shape input)
		(at 48.26 220.98 90)
		(fields_autoplaced yes)
		(effects
			(font
				(size 1.27 1.27)
			)
			(justify left)
		)
		(property "Intersheetrefs" "${INTERSHEET_REFS}"
			(at -49.53 -10.795 0)
			(effects
				(font
					(size 1.27 1.27)
				)
				(hide yes)
			)
		)
	)
	(global_label "USR_LED1"
		(shape input)
		(at 186.69 231.14 180)
		(fields_autoplaced yes)
		(effects
			(font
				(size 1.27 1.27)
			)
			(justify right)
		)
		(property "Intersheetrefs" "${INTERSHEET_REFS}"
			(at -1.27 -0.635 0)
			(effects
				(font
					(size 1.27 1.27)
				)
				(hide yes)
			)
		)
	)
	(global_label "TMDS_CLK_N"
		(shape input)
		(at 283.21 59.69 180)
		(fields_autoplaced yes)
		(effects
			(font
				(size 1.27 1.27)
			)
			(justify right)
		)
		(property "Intersheetrefs" "${INTERSHEET_REFS}"
			(at 227.33 -285.75 90)
			(effects
				(font
					(size 1.27 1.27)
				)
				(justify left)
				(hide yes)
			)
		)
	)
	(global_label "DBG_USB_P"
		(shape input)
		(at 200.66 130.81 180)
		(fields_autoplaced yes)
		(effects
			(font
				(size 1.27 1.27)
			)
			(justify right)
		)
		(property "Intersheetrefs" "${INTERSHEET_REFS}"
			(at 4.445 264.16 0)
			(effects
				(font
					(size 1.27 1.27)
				)
				(hide yes)
			)
		)
	)
	(global_label "TMDS_D1_N"
		(shape input)
		(at 283.21 49.53 180)
		(fields_autoplaced yes)
		(effects
			(font
				(size 1.27 1.27)
			)
			(justify right)
		)
		(property "Intersheetrefs" "${INTERSHEET_REFS}"
			(at 227.33 -323.85 90)
			(effects
				(font
					(size 1.27 1.27)
				)
				(justify left)
				(hide yes)
			)
		)
	)
	(global_label "AUX_JTAG_TCK"
		(shape input)
		(at 144.145 66.675 0)
		(fields_autoplaced yes)
		(effects
			(font
				(size 1.27 1.27)
			)
			(justify left)
		)
		(property "Intersheetrefs" "${INTERSHEET_REFS}"
			(at -13.97 -31.115 0)
			(effects
				(font
					(size 1.27 1.27)
				)
				(hide yes)
			)
		)
	)
	(global_label "3V3_SYS"
		(shape input)
		(at 29.21 45.72 180)
		(fields_autoplaced yes)
		(effects
			(font
				(size 1.27 1.27)
			)
			(justify right)
		)
		(property "Intersheetrefs" "${INTERSHEET_REFS}"
			(at -183.515 -13.97 0)
			(effects
				(font
					(size 1.27 1.27)
				)
				(justify right)
				(hide yes)
			)
		)
	)
	(global_label "3V3_SYS"
		(shape input)
		(at 153.67 260.35 180)
		(fields_autoplaced yes)
		(effects
			(font
				(size 1.27 1.27)
			)
			(justify right)
		)
		(property "Intersheetrefs" "${INTERSHEET_REFS}"
			(at -31.75 -3.175 0)
			(effects
				(font
					(size 1.27 1.27)
				)
				(hide yes)
			)
		)
	)
	(global_label "USR_BTN4"
		(shape input)
		(at 91.44 240.665 0)
		(fields_autoplaced yes)
		(effects
			(font
				(size 1.27 1.27)
			)
			(justify left)
		)
		(property "Intersheetrefs" "${INTERSHEET_REFS}"
			(at -49.53 -10.795 0)
			(effects
				(font
					(size 1.27 1.27)
				)
				(hide yes)
			)
		)
	)
	(global_label "USR_LED3"
		(shape input)
		(at 186.69 270.51 180)
		(fields_autoplaced yes)
		(effects
			(font
				(size 1.27 1.27)
			)
			(justify right)
		)
		(property "Intersheetrefs" "${INTERSHEET_REFS}"
			(at -1.27 -0.635 0)
			(effects
				(font
					(size 1.27 1.27)
				)
				(hide yes)
			)
		)
	)
	(global_label "TDO_JTAG"
		(shape input)
		(at 144.145 50.165 0)
		(fields_autoplaced yes)
		(effects
			(font
				(size 1.27 1.27)
			)
			(justify left)
		)
		(property "Intersheetrefs" "${INTERSHEET_REFS}"
			(at -13.97 -31.115 0)
			(effects
				(font
					(size 1.27 1.27)
				)
				(hide yes)
			)
		)
	)
	(global_label "3V3_SYS"
		(shape input)
		(at 299.085 150.495 180)
		(fields_autoplaced yes)
		(effects
			(font
				(size 1.27 1.27)
			)
			(justify right)
		)
		(property "Intersheetrefs" "${INTERSHEET_REFS}"
			(at 142.875 488.315 0)
			(effects
				(font
					(size 1.27 1.27)
				)
				(hide yes)
			)
		)
	)
	(global_label "TDI_JTAG"
		(shape input)
		(at 144.145 47.625 0)
		(fields_autoplaced yes)
		(effects
			(font
				(size 1.27 1.27)
			)
			(justify left)
		)
		(property "Intersheetrefs" "${INTERSHEET_REFS}"
			(at -13.97 -31.115 0)
			(effects
				(font
					(size 1.27 1.27)
				)
				(hide yes)
			)
		)
	)
	(global_label "USR_LED5"
		(shape input)
		(at 250.19 250.825 180)
		(fields_autoplaced yes)
		(effects
			(font
				(size 1.27 1.27)
			)
			(justify right)
		)
		(property "Intersheetrefs" "${INTERSHEET_REFS}"
			(at 6.985 -0.635 0)
			(effects
				(font
					(size 1.27 1.27)
				)
				(hide yes)
			)
		)
	)
	(global_label "UART1_TX"
		(shape input)
		(at 144.145 112.395 0)
		(fields_autoplaced yes)
		(effects
			(font
				(size 1.27 1.27)
			)
			(justify left)
		)
		(property "Intersheetrefs" "${INTERSHEET_REFS}"
			(at -13.97 -31.115 0)
			(effects
				(font
					(size 1.27 1.27)
				)
				(hide yes)
			)
		)
	)
	(global_label "USR_LED2"
		(shape input)
		(at 187.325 250.825 180)
		(fields_autoplaced yes)
		(effects
			(font
				(size 1.27 1.27)
			)
			(justify right)
		)
		(property "Intersheetrefs" "${INTERSHEET_REFS}"
			(at -1.27 -0.635 0)
			(effects
				(font
					(size 1.27 1.27)
				)
				(hide yes)
			)
		)
	)
	(global_label "3V3_SYS"
		(shape input)
		(at 154.305 240.665 180)
		(fields_autoplaced yes)
		(effects
			(font
				(size 1.27 1.27)
			)
			(justify right)
		)
		(property "Intersheetrefs" "${INTERSHEET_REFS}"
			(at -31.75 -3.175 0)
			(effects
				(font
					(size 1.27 1.27)
				)
				(hide yes)
			)
		)
	)
	(global_label "SD_DAT0"
		(shape input)
		(at 299.085 181.61 180)
		(fields_autoplaced yes)
		(effects
			(font
				(size 1.27 1.27)
			)
			(justify right)
		)
		(property "Intersheetrefs" "${INTERSHEET_REFS}"
			(at 16.51 -10.795 0)
			(effects
				(font
					(size 1.27 1.27)
				)
				(hide yes)
			)
		)
	)
	(global_label "USR_BTN2"
		(shape input)
		(at 91.44 234.315 0)
		(fields_autoplaced yes)
		(effects
			(font
				(size 1.27 1.27)
			)
			(justify left)
		)
		(property "Intersheetrefs" "${INTERSHEET_REFS}"
			(at -49.53 -10.795 0)
			(effects
				(font
					(size 1.27 1.27)
				)
				(hide yes)
			)
		)
	)
	(global_label "3V3_SYS"
		(shape input)
		(at 278.765 69.85 180)
		(fields_autoplaced yes)
		(effects
			(font
				(size 1.27 1.27)
			)
			(justify right)
		)
		(property "Intersheetrefs" "${INTERSHEET_REFS}"
			(at 214.63 388.62 0)
			(effects
				(font
					(size 1.27 1.27)
				)
				(justify right)
				(hide yes)
			)
		)
	)
	(global_label "VBUS"
		(shape input)
		(at 200.025 125.73 180)
		(fields_autoplaced yes)
		(effects
			(font
				(size 1.27 1.27)
			)
			(justify right)
		)
		(property "Intersheetrefs" "${INTERSHEET_REFS}"
			(at 83.185 352.425 0)
			(effects
				(font
					(size 1.27 1.27)
				)
				(hide yes)
			)
		)
	)
	(global_label "SD_DAT2"
		(shape input)
		(at 299.085 166.37 180)
		(fields_autoplaced yes)
		(effects
			(font
				(size 1.27 1.27)
			)
			(justify right)
		)
		(property "Intersheetrefs" "${INTERSHEET_REFS}"
			(at 16.51 -10.795 0)
			(effects
				(font
					(size 1.27 1.27)
				)
				(hide yes)
			)
		)
	)
	(global_label "3V3_SYS"
		(shape input)
		(at 61.595 220.98 90)
		(fields_autoplaced yes)
		(effects
			(font
				(size 1.27 1.27)
			)
			(justify left)
		)
		(property "Intersheetrefs" "${INTERSHEET_REFS}"
			(at -49.53 -10.795 0)
			(effects
				(font
					(size 1.27 1.27)
				)
				(hide yes)
			)
		)
	)
	(global_label "TMDS_D0_N"
		(shape input)
		(at 283.21 54.61 180)
		(fields_autoplaced yes)
		(effects
			(font
				(size 1.27 1.27)
			)
			(justify right)
		)
		(property "Intersheetrefs" "${INTERSHEET_REFS}"
			(at 227.33 -304.8 90)
			(effects
				(font
					(size 1.27 1.27)
				)
				(justify left)
				(hide yes)
			)
		)
	)
	(global_label "3V3_SYS"
		(shape input)
		(at 75.565 81.915 180)
		(fields_autoplaced yes)
		(effects
			(font
				(size 1.27 1.27)
			)
			(justify right)
		)
		(property "Intersheetrefs" "${INTERSHEET_REFS}"
			(at -1.905 -55.245 0)
			(effects
				(font
					(size 1.27 1.27)
				)
				(hide yes)
			)
		)
	)
	(global_label "SD_CMD"
		(shape input)
		(at 299.085 171.45 180)
		(fields_autoplaced yes)
		(effects
			(font
				(size 1.27 1.27)
			)
			(justify right)
		)
		(property "Intersheetrefs" "${INTERSHEET_REFS}"
			(at 16.51 -10.795 0)
			(effects
				(font
					(size 1.27 1.27)
				)
				(hide yes)
			)
		)
	)
	(global_label "UART1_RX"
		(shape input)
		(at 144.145 109.855 0)
		(fields_autoplaced yes)
		(effects
			(font
				(size 1.27 1.27)
			)
			(justify left)
		)
		(property "Intersheetrefs" "${INTERSHEET_REFS}"
			(at -13.97 -31.115 0)
			(effects
				(font
					(size 1.27 1.27)
				)
				(hide yes)
			)
		)
	)
	(global_label "SD_DAT3"
		(shape input)
		(at 299.085 168.91 180)
		(fields_autoplaced yes)
		(effects
			(font
				(size 1.27 1.27)
			)
			(justify right)
		)
		(property "Intersheetrefs" "${INTERSHEET_REFS}"
			(at 16.51 -10.795 0)
			(effects
				(font
					(size 1.27 1.27)
				)
				(hide yes)
			)
		)
	)
	(global_label "DBG_USB_N"
		(shape input)
		(at 85.725 70.485 180)
		(fields_autoplaced yes)
		(effects
			(font
				(size 1.27 1.27)
			)
			(justify right)
		)
		(property "Intersheetrefs" "${INTERSHEET_REFS}"
			(at 2.54 -51.435 0)
			(effects
				(font
					(size 1.27 1.27)
				)
				(hide yes)
			)
		)
	)
	(global_label "3V3_SYS"
		(shape input)
		(at 339.09 173.99 180)
		(fields_autoplaced yes)
		(effects
			(font
				(size 1.27 1.27)
			)
			(justify right)
		)
		(property "Intersheetrefs" "${INTERSHEET_REFS}"
			(at 182.88 511.81 0)
			(effects
				(font
					(size 1.27 1.27)
				)
				(hide yes)
			)
		)
	)
	(global_label "TMDS_D2_P"
		(shape input)
		(at 283.21 41.91 180)
		(fields_autoplaced yes)
		(effects
			(font
				(size 1.27 1.27)
			)
			(justify right)
		)
		(property "Intersheetrefs" "${INTERSHEET_REFS}"
			(at 227.33 -352.425 90)
			(effects
				(font
					(size 1.27 1.27)
				)
				(justify left)
				(hide yes)
			)
		)
	)
	(global_label "DBG_USB_N"
		(shape input)
		(at 200.66 133.35 180)
		(fields_autoplaced yes)
		(effects
			(font
				(size 1.27 1.27)
			)
			(justify right)
		)
		(property "Intersheetrefs" "${INTERSHEET_REFS}"
			(at 4.445 264.16 0)
			(effects
				(font
					(size 1.27 1.27)
				)
				(hide yes)
			)
		)
	)
	(global_label "AUX_JTAG_TMS"
		(shape input)
		(at 144.145 74.295 0)
		(fields_autoplaced yes)
		(effects
			(font
				(size 1.27 1.27)
			)
			(justify left)
		)
		(property "Intersheetrefs" "${INTERSHEET_REFS}"
			(at -13.97 -31.115 0)
			(effects
				(font
					(size 1.27 1.27)
				)
				(hide yes)
			)
		)
	)
	(global_label "3V3_SYS"
		(shape input)
		(at 74.295 220.345 90)
		(fields_autoplaced yes)
		(effects
			(font
				(size 1.27 1.27)
			)
			(justify left)
		)
		(property "Intersheetrefs" "${INTERSHEET_REFS}"
			(at -49.53 -10.795 0)
			(effects
				(font
					(size 1.27 1.27)
				)
				(hide yes)
			)
		)
	)
	(global_label "3V3_SYS"
		(shape input)
		(at 370.84 175.26 90)
		(fields_autoplaced yes)
		(effects
			(font
				(size 1.27 1.27)
			)
			(justify left)
		)
		(property "Intersheetrefs" "${INTERSHEET_REFS}"
			(at 33.02 19.05 0)
			(effects
				(font
					(size 1.27 1.27)
				)
				(hide yes)
			)
		)
	)
	(global_label "DBG_USB_P"
		(shape input)
		(at 85.725 67.945 180)
		(fields_autoplaced yes)
		(effects
			(font
				(size 1.27 1.27)
			)
			(justify right)
		)
		(property "Intersheetrefs" "${INTERSHEET_REFS}"
			(at 2.54 -56.515 0)
			(effects
				(font
					(size 1.27 1.27)
				)
				(hide yes)
			)
		)
	)
	(symbol
		(lib_id "antmicroResistors0402:R_4k7_0402")
		(at 86.995 223.52 270)
		(unit 1)
		(exclude_from_sim no)
		(in_bom yes)
		(on_board yes)
		(dnp no)
		(property "Reference" "R12"
			(at 88.265 226.06 90)
			(effects
				(font
					(size 1.27 1.27)
					(thickness 0.15)
				)
				(justify left bottom)
			)
		)
		(property "Value" "R_4k7_0402"
			(at 74.295 243.84 0)
			(effects
				(font
					(size 1.27 1.27)
					(thickness 0.15)
				)
				(justify left bottom)
				(hide yes)
			)
		)
		(property "Footprint" "antmicro-footprints:R_0402_1005Metric"
			(at 71.755 243.84 0)
			(effects
				(font
					(size 1.27 1.27)
					(thickness 0.15)
				)
				(justify left bottom)
				(hide yes)
			)
		)
		(property "Datasheet" "https://www.bourns.com/docs/product-datasheets/cr.pdf"
			(at 69.215 243.84 0)
			(effects
				(font
					(size 1.27 1.27)
					(thickness 0.15)
				)
				(justify left bottom)
				(hide yes)
			)
		)
		(property "Description" ""
			(at 86.995 223.52 0)
			(effects
				(font
					(size 1.27 1.27)
				)
			)
		)
		(property "Manufacturer" "Bourns"
			(at 64.135 243.84 0)
			(effects
				(font
					(size 1.27 1.27)
					(thickness 0.15)
				)
				(justify left bottom)
				(hide yes)
			)
		)
		(property "MPN" "CR0402-FX-4701GLF"
			(at 66.675 243.84 0)
			(effects
				(font
					(size 1.27 1.27)
					(thickness 0.15)
				)
				(justify left bottom)
				(hide yes)
			)
		)
		(property "Val" "4k7"
			(at 88.265 227.965 90)
			(effects
				(font
					(size 1.27 1.27)
					(thickness 0.15)
				)
				(justify left bottom)
			)
		)
		(property "License" "Apache-2.0"
			(at 61.595 243.84 0)
			(effects
				(font
					(size 1.27 1.27)
					(thickness 0.15)
				)
				(justify left bottom)
				(hide yes)
			)
		)
		(property "Author" "Antmicro"
			(at 59.055 243.84 0)
			(effects
				(font
					(size 1.27 1.27)
					(thickness 0.15)
				)
				(justify left bottom)
				(hide yes)
			)
		)
		(property "Tolerance" "1%"
			(at 76.835 243.84 0)
			(effects
				(font
					(size 1.27 1.27)
				)
				(justify left bottom)
				(hide yes)
			)
		)
		(pin "1"
		)
		(pin "2"
		)
		(instances
			(project "lpddr4-test-board"
				(path ""
					(reference "R12")
					(unit 1)
				)
			)
		)
	)
	(symbol
		(lib_id "antmicropower:GND")
		(at 86.995 259.08 0)
		(unit 1)
		(exclude_from_sim no)
		(in_bom yes)
		(on_board yes)
		(dnp no)
		(property "Reference" "#PWR030"
			(at 95.885 261.62 0)
			(effects
				(font
					(size 1.27 1.27)
					(thickness 0.15)
				)
				(justify left bottom)
				(hide yes)
			)
		)
		(property "Value" "GND"
			(at 85.09 263.525 0)
			(effects
				(font
					(size 1.27 1.27)
					(thickness 0.15)
				)
				(justify left bottom)
			)
		)
		(property "Footprint" ""
			(at 95.885 266.7 0)
			(effects
				(font
					(size 1.27 1.27)
					(thickness 0.15)
				)
				(justify left bottom)
				(hide yes)
			)
		)
		(property "Datasheet" ""
			(at 95.885 271.78 0)
			(effects
				(font
					(size 1.27 1.27)
					(thickness 0.15)
				)
				(justify left bottom)
				(hide yes)
			)
		)
		(property "Description" ""
			(at 86.995 259.08 0)
			(effects
				(font
					(size 1.27 1.27)
				)
			)
		)
		(property "Author" "Antmicro"
			(at 95.885 266.7 0)
			(effects
				(font
					(size 1.27 1.27)
					(thickness 0.15)
				)
				(justify left bottom)
				(hide yes)
			)
		)
		(property "License" "Apache-2.0"
			(at 95.885 269.24 0)
			(effects
				(font
					(size 1.27 1.27)
					(thickness 0.15)
				)
				(justify left bottom)
				(hide yes)
			)
		)
		(pin "1"
		)
		(instances
			(project "lpddr4-test-board"
				(path ""
					(reference "#PWR030")
					(unit 1)
				)
			)
		)
	)
	(symbol
		(lib_id "antmicroPushbuttonSwitches:SW_B3U-1000P_SMD")
		(at 86.995 245.745 270)
		(unit 1)
		(exclude_from_sim no)
		(in_bom yes)
		(on_board yes)
		(dnp no)
		(property "Reference" "USR_BTN4"
			(at 85.09 255.905 0)
			(effects
				(font
					(size 1.27 1.27)
					(thickness 0.15)
				)
				(justify right top)
			)
		)
		(property "Value" "SW_B3U-1000P"
			(at 92.075 259.08 0)
			(effects
				(font
					(size 1.27 1.27)
					(thickness 0.15)
				)
				(justify right top)
			)
		)
		(property "Footprint" "antmicro-footprints:SW_B3U-1000P_SMD"
			(at 79.375 271.145 0)
			(effects
				(font
					(size 1.27 1.27)
					(thickness 0.15)
				)
				(justify left bottom)
				(hide yes)
			)
		)
		(property "Datasheet" "https://omronfs.omron.com/en_US/ecb/products/pdf/en-b3u.pdf"
			(at 76.835 271.145 0)
			(effects
				(font
					(size 1.27 1.27)
					(thickness 0.15)
				)
				(justify left bottom)
				(hide yes)
			)
		)
		(property "Description" ""
			(at 86.995 245.745 0)
			(effects
				(font
					(size 1.27 1.27)
				)
			)
		)
		(property "MPN" "B3U-1000P"
			(at 81.28 245.11 0)
			(effects
				(font
					(size 1.27 1.27)
					(thickness 0.15)
				)
				(justify left bottom)
			)
		)
		(property "Manufacturer" "Omron"
			(at 71.755 271.145 0)
			(effects
				(font
					(size 1.27 1.27)
					(thickness 0.15)
				)
				(justify left bottom)
				(hide yes)
			)
		)
		(property "Author" "Antmicro"
			(at 69.215 271.145 0)
			(effects
				(font
					(size 1.27 1.27)
					(thickness 0.15)
				)
				(justify left bottom)
				(hide yes)
			)
		)
		(property "License" "Apache-2.0"
			(at 66.675 271.145 0)
			(effects
				(font
					(size 1.27 1.27)
					(thickness 0.15)
				)
				(justify left bottom)
				(hide yes)
			)
		)
		(pin "1"
		)
		(pin "2"
		)
		(instances
			(project "lpddr4-test-board"
				(path ""
					(reference "USR_BTN4")
					(unit 1)
				)
			)
		)
	)
	(symbol
		(lib_id "antmicroPushbuttonSwitches:SW_B3U-1000P_SMD")
		(at 61.595 245.745 270)
		(unit 1)
		(exclude_from_sim no)
		(in_bom yes)
		(on_board yes)
		(dnp no)
		(property "Reference" "USR_BTN2"
			(at 59.69 255.905 0)
			(effects
				(font
					(size 1.27 1.27)
					(thickness 0.15)
				)
				(justify right top)
			)
		)
		(property "Value" "SW_B3U-1000P"
			(at 66.675 259.08 0)
			(effects
				(font
					(size 1.27 1.27)
					(thickness 0.15)
				)
				(justify right top)
			)
		)
		(property "Footprint" "antmicro-footprints:SW_B3U-1000P_SMD"
			(at 53.975 271.145 0)
			(effects
				(font
					(size 1.27 1.27)
					(thickness 0.15)
				)
				(justify left bottom)
				(hide yes)
			)
		)
		(property "Datasheet" "https://omronfs.omron.com/en_US/ecb/products/pdf/en-b3u.pdf"
			(at 51.435 271.145 0)
			(effects
				(font
					(size 1.27 1.27)
					(thickness 0.15)
				)
				(justify left bottom)
				(hide yes)
			)
		)
		(property "Description" ""
			(at 61.595 245.745 0)
			(effects
				(font
					(size 1.27 1.27)
				)
			)
		)
		(property "MPN" "B3U-1000P"
			(at 55.88 245.11 0)
			(effects
				(font
					(size 1.27 1.27)
					(thickness 0.15)
				)
				(justify left bottom)
			)
		)
		(property "Manufacturer" "Omron"
			(at 46.355 271.145 0)
			(effects
				(font
					(size 1.27 1.27)
					(thickness 0.15)
				)
				(justify left bottom)
				(hide yes)
			)
		)
		(property "Author" "Antmicro"
			(at 43.815 271.145 0)
			(effects
				(font
					(size 1.27 1.27)
					(thickness 0.15)
				)
				(justify left bottom)
				(hide yes)
			)
		)
		(property "License" "Apache-2.0"
			(at 41.275 271.145 0)
			(effects
				(font
					(size 1.27 1.27)
					(thickness 0.15)
				)
				(justify left bottom)
				(hide yes)
			)
		)
		(pin "1"
		)
		(pin "2"
		)
		(instances
			(project "lpddr4-test-board"
				(path ""
					(reference "USR_BTN2")
					(unit 1)
				)
			)
		)
	)
	(symbol
		(lib_id "antmicropower:GND")
		(at 61.595 259.08 0)
		(unit 1)
		(exclude_from_sim no)
		(in_bom yes)
		(on_board yes)
		(dnp no)
		(property "Reference" "#PWR028"
			(at 70.485 261.62 0)
			(effects
				(font
					(size 1.27 1.27)
					(thickness 0.15)
				)
				(justify left bottom)
				(hide yes)
			)
		)
		(property "Value" "GND"
			(at 59.69 263.525 0)
			(effects
				(font
					(size 1.27 1.27)
					(thickness 0.15)
				)
				(justify left bottom)
			)
		)
		(property "Footprint" ""
			(at 70.485 266.7 0)
			(effects
				(font
					(size 1.27 1.27)
					(thickness 0.15)
				)
				(justify left bottom)
				(hide yes)
			)
		)
		(property "Datasheet" ""
			(at 70.485 271.78 0)
			(effects
				(font
					(size 1.27 1.27)
					(thickness 0.15)
				)
				(justify left bottom)
				(hide yes)
			)
		)
		(property "Description" ""
			(at 61.595 259.08 0)
			(effects
				(font
					(size 1.27 1.27)
				)
			)
		)
		(property "Author" "Antmicro"
			(at 70.485 266.7 0)
			(effects
				(font
					(size 1.27 1.27)
					(thickness 0.15)
				)
				(justify left bottom)
				(hide yes)
			)
		)
		(property "License" "Apache-2.0"
			(at 70.485 269.24 0)
			(effects
				(font
					(size 1.27 1.27)
					(thickness 0.15)
				)
				(justify left bottom)
				(hide yes)
			)
		)
		(pin "1"
		)
		(instances
			(project "lpddr4-test-board"
				(path ""
					(reference "#PWR028")
					(unit 1)
				)
			)
		)
	)
	(symbol
		(lib_id "antmicroResistors0402:R_4k7_0402")
		(at 61.595 223.52 270)
		(unit 1)
		(exclude_from_sim no)
		(in_bom yes)
		(on_board yes)
		(dnp no)
		(property "Reference" "R10"
			(at 62.865 226.06 90)
			(effects
				(font
					(size 1.27 1.27)
					(thickness 0.15)
				)
				(justify left bottom)
			)
		)
		(property "Value" "R_4k7_0402"
			(at 48.895 243.84 0)
			(effects
				(font
					(size 1.27 1.27)
					(thickness 0.15)
				)
				(justify left bottom)
				(hide yes)
			)
		)
		(property "Footprint" "antmicro-footprints:R_0402_1005Metric"
			(at 46.355 243.84 0)
			(effects
				(font
					(size 1.27 1.27)
					(thickness 0.15)
				)
				(justify left bottom)
				(hide yes)
			)
		)
		(property "Datasheet" "https://www.bourns.com/docs/product-datasheets/cr.pdf"
			(at 43.815 243.84 0)
			(effects
				(font
					(size 1.27 1.27)
					(thickness 0.15)
				)
				(justify left bottom)
				(hide yes)
			)
		)
		(property "Description" ""
			(at 61.595 223.52 0)
			(effects
				(font
					(size 1.27 1.27)
				)
			)
		)
		(property "Manufacturer" "Bourns"
			(at 38.735 243.84 0)
			(effects
				(font
					(size 1.27 1.27)
					(thickness 0.15)
				)
				(justify left bottom)
				(hide yes)
			)
		)
		(property "MPN" "CR0402-FX-4701GLF"
			(at 41.275 243.84 0)
			(effects
				(font
					(size 1.27 1.27)
					(thickness 0.15)
				)
				(justify left bottom)
				(hide yes)
			)
		)
		(property "Val" "4k7"
			(at 62.865 227.965 90)
			(effects
				(font
					(size 1.27 1.27)
					(thickness 0.15)
				)
				(justify left bottom)
			)
		)
		(property "License" "Apache-2.0"
			(at 36.195 243.84 0)
			(effects
				(font
					(size 1.27 1.27)
					(thickness 0.15)
				)
				(justify left bottom)
				(hide yes)
			)
		)
		(property "Author" "Antmicro"
			(at 33.655 243.84 0)
			(effects
				(font
					(size 1.27 1.27)
					(thickness 0.15)
				)
				(justify left bottom)
				(hide yes)
			)
		)
		(property "Tolerance" "1%"
			(at 51.435 243.84 0)
			(effects
				(font
					(size 1.27 1.27)
				)
				(justify left bottom)
				(hide yes)
			)
		)
		(pin "1"
		)
		(pin "2"
		)
		(instances
			(project "lpddr4-test-board"
				(path ""
					(reference "R10")
					(unit 1)
				)
			)
		)
	)
	(symbol
		(lib_id "antmicroPushbuttonSwitches:SW_B3U-1000P_SMD")
		(at 48.26 245.745 270)
		(unit 1)
		(exclude_from_sim no)
		(in_bom yes)
		(on_board yes)
		(dnp no)
		(property "Reference" "USR_BTN1"
			(at 46.355 255.905 0)
			(effects
				(font
					(size 1.27 1.27)
					(thickness 0.15)
				)
				(justify right top)
			)
		)
		(property "Value" "SW_B3U-1000P"
			(at 53.34 259.08 0)
			(effects
				(font
					(size 1.27 1.27)
					(thickness 0.15)
				)
				(justify right top)
			)
		)
		(property "Footprint" "antmicro-footprints:SW_B3U-1000P_SMD"
			(at 40.64 271.145 0)
			(effects
				(font
					(size 1.27 1.27)
					(thickness 0.15)
				)
				(justify left bottom)
				(hide yes)
			)
		)
		(property "Datasheet" "https://omronfs.omron.com/en_US/ecb/products/pdf/en-b3u.pdf"
			(at 38.1 271.145 0)
			(effects
				(font
					(size 1.27 1.27)
					(thickness 0.15)
				)
				(justify left bottom)
				(hide yes)
			)
		)
		(property "Description" ""
			(at 48.26 245.745 0)
			(effects
				(font
					(size 1.27 1.27)
				)
			)
		)
		(property "MPN" "B3U-1000P"
			(at 43.18 245.11 0)
			(effects
				(font
					(size 1.27 1.27)
					(thickness 0.15)
				)
				(justify left bottom)
			)
		)
		(property "Manufacturer" "Omron"
			(at 33.02 271.145 0)
			(effects
				(font
					(size 1.27 1.27)
					(thickness 0.15)
				)
				(justify left bottom)
				(hide yes)
			)
		)
		(property "Author" "Antmicro"
			(at 30.48 271.145 0)
			(effects
				(font
					(size 1.27 1.27)
					(thickness 0.15)
				)
				(justify left bottom)
				(hide yes)
			)
		)
		(property "License" "Apache-2.0"
			(at 27.94 271.145 0)
			(effects
				(font
					(size 1.27 1.27)
					(thickness 0.15)
				)
				(justify left bottom)
				(hide yes)
			)
		)
		(pin "1"
		)
		(pin "2"
		)
		(instances
			(project "lpddr4-test-board"
				(path ""
					(reference "USR_BTN1")
					(unit 1)
				)
			)
		)
	)
	(symbol
		(lib_id "antmicropower:GND")
		(at 48.26 259.08 0)
		(unit 1)
		(exclude_from_sim no)
		(in_bom yes)
		(on_board yes)
		(dnp no)
		(property "Reference" "#PWR026"
			(at 57.15 261.62 0)
			(effects
				(font
					(size 1.27 1.27)
					(thickness 0.15)
				)
				(justify left bottom)
				(hide yes)
			)
		)
		(property "Value" "GND"
			(at 46.355 263.525 0)
			(effects
				(font
					(size 1.27 1.27)
					(thickness 0.15)
				)
				(justify left bottom)
			)
		)
		(property "Footprint" ""
			(at 57.15 266.7 0)
			(effects
				(font
					(size 1.27 1.27)
					(thickness 0.15)
				)
				(justify left bottom)
				(hide yes)
			)
		)
		(property "Datasheet" ""
			(at 57.15 271.78 0)
			(effects
				(font
					(size 1.27 1.27)
					(thickness 0.15)
				)
				(justify left bottom)
				(hide yes)
			)
		)
		(property "Description" ""
			(at 48.26 259.08 0)
			(effects
				(font
					(size 1.27 1.27)
				)
			)
		)
		(property "Author" "Antmicro"
			(at 57.15 266.7 0)
			(effects
				(font
					(size 1.27 1.27)
					(thickness 0.15)
				)
				(justify left bottom)
				(hide yes)
			)
		)
		(property "License" "Apache-2.0"
			(at 57.15 269.24 0)
			(effects
				(font
					(size 1.27 1.27)
					(thickness 0.15)
				)
				(justify left bottom)
				(hide yes)
			)
		)
		(pin "1"
		)
		(instances
			(project "lpddr4-test-board"
				(path ""
					(reference "#PWR026")
					(unit 1)
				)
			)
		)
	)
	(symbol
		(lib_id "antmicroResistors0402:R_4k7_0402")
		(at 48.26 223.52 270)
		(unit 1)
		(exclude_from_sim no)
		(in_bom yes)
		(on_board yes)
		(dnp no)
		(property "Reference" "R9"
			(at 49.53 226.06 90)
			(effects
				(font
					(size 1.27 1.27)
					(thickness 0.15)
				)
				(justify left bottom)
			)
		)
		(property "Value" "R_4k7_0402"
			(at 35.56 243.84 0)
			(effects
				(font
					(size 1.27 1.27)
					(thickness 0.15)
				)
				(justify left bottom)
				(hide yes)
			)
		)
		(property "Footprint" "antmicro-footprints:R_0402_1005Metric"
			(at 33.02 243.84 0)
			(effects
				(font
					(size 1.27 1.27)
					(thickness 0.15)
				)
				(justify left bottom)
				(hide yes)
			)
		)
		(property "Datasheet" "https://www.bourns.com/docs/product-datasheets/cr.pdf"
			(at 30.48 243.84 0)
			(effects
				(font
					(size 1.27 1.27)
					(thickness 0.15)
				)
				(justify left bottom)
				(hide yes)
			)
		)
		(property "Description" ""
			(at 48.26 223.52 0)
			(effects
				(font
					(size 1.27 1.27)
				)
			)
		)
		(property "Manufacturer" "Bourns"
			(at 25.4 243.84 0)
			(effects
				(font
					(size 1.27 1.27)
					(thickness 0.15)
				)
				(justify left bottom)
				(hide yes)
			)
		)
		(property "MPN" "CR0402-FX-4701GLF"
			(at 27.94 243.84 0)
			(effects
				(font
					(size 1.27 1.27)
					(thickness 0.15)
				)
				(justify left bottom)
				(hide yes)
			)
		)
		(property "Val" "4k7"
			(at 49.53 227.965 90)
			(effects
				(font
					(size 1.27 1.27)
					(thickness 0.15)
				)
				(justify left bottom)
			)
		)
		(property "License" "Apache-2.0"
			(at 22.86 243.84 0)
			(effects
				(font
					(size 1.27 1.27)
					(thickness 0.15)
				)
				(justify left bottom)
				(hide yes)
			)
		)
		(property "Author" "Antmicro"
			(at 20.32 243.84 0)
			(effects
				(font
					(size 1.27 1.27)
					(thickness 0.15)
				)
				(justify left bottom)
				(hide yes)
			)
		)
		(property "Tolerance" "1%"
			(at 38.1 243.84 0)
			(effects
				(font
					(size 1.27 1.27)
				)
				(justify left bottom)
				(hide yes)
			)
		)
		(pin "1"
		)
		(pin "2"
		)
		(instances
			(project "lpddr4-test-board"
				(path ""
					(reference "R9")
					(unit 1)
				)
			)
		)
	)
	(symbol
		(lib_id "antmicroResistors0402:R_22R_0402")
		(at 133.985 66.675 0)
		(unit 1)
		(exclude_from_sim no)
		(in_bom yes)
		(on_board yes)
		(dnp no)
		(property "Reference" "R17"
			(at 139.065 66.675 0)
			(effects
				(font
					(size 1.27 1.27)
					(thickness 0.15)
				)
				(justify left bottom)
			)
		)
		(property "Value" "R_22R_0402"
			(at 154.305 79.375 0)
			(effects
				(font
					(size 1.27 1.27)
					(thickness 0.15)
				)
				(justify left bottom)
				(hide yes)
			)
		)
		(property "Footprint" "antmicro-footprints:R_0402_1005Metric"
			(at 154.305 81.915 0)
			(effects
				(font
					(size 1.27 1.27)
					(thickness 0.15)
				)
				(justify left bottom)
				(hide yes)
			)
		)
		(property "Datasheet" "https://www.bourns.com/docs/product-datasheets/cr.pdf"
			(at 154.305 84.455 0)
			(effects
				(font
					(size 1.27 1.27)
					(thickness 0.15)
				)
				(justify left bottom)
				(hide yes)
			)
		)
		(property "Description" ""
			(at 133.985 66.675 0)
			(effects
				(font
					(size 1.27 1.27)
				)
			)
		)
		(property "Manufacturer" "Bourns"
			(at 154.305 89.535 0)
			(effects
				(font
					(size 1.27 1.27)
					(thickness 0.15)
				)
				(justify left bottom)
				(hide yes)
			)
		)
		(property "MPN" "CR0402-FX-22R0GLF"
			(at 154.305 86.995 0)
			(effects
				(font
					(size 1.27 1.27)
					(thickness 0.15)
				)
				(justify left bottom)
				(hide yes)
			)
		)
		(property "Val" "22R"
			(at 130.175 66.675 0)
			(effects
				(font
					(size 1.27 1.27)
					(thickness 0.15)
				)
				(justify left bottom)
			)
		)
		(property "License" "Apache-2.0"
			(at 154.305 92.075 0)
			(effects
				(font
					(size 1.27 1.27)
					(thickness 0.15)
				)
				(justify left bottom)
				(hide yes)
			)
		)
		(property "Author" "Antmicro"
			(at 154.305 94.615 0)
			(effects
				(font
					(size 1.27 1.27)
					(thickness 0.15)
				)
				(justify left bottom)
				(hide yes)
			)
		)
		(property "Tolerance" "1%"
			(at 154.305 76.835 0)
			(effects
				(font
					(size 1.27 1.27)
				)
				(justify left bottom)
				(hide yes)
			)
		)
		(pin "1"
		)
		(pin "2"
		)
		(instances
			(project "lpddr4-test-board"
				(path ""
					(reference "R17")
					(unit 1)
				)
			)
		)
	)
	(symbol
		(lib_id "antmicroResistors0402:R_22R_0402")
		(at 133.985 69.215 0)
		(unit 1)
		(exclude_from_sim no)
		(in_bom yes)
		(on_board yes)
		(dnp no)
		(property "Reference" "R18"
			(at 139.065 69.215 0)
			(effects
				(font
					(size 1.27 1.27)
					(thickness 0.15)
				)
				(justify left bottom)
			)
		)
		(property "Value" "R_22R_0402"
			(at 154.305 81.915 0)
			(effects
				(font
					(size 1.27 1.27)
					(thickness 0.15)
				)
				(justify left bottom)
				(hide yes)
			)
		)
		(property "Footprint" "antmicro-footprints:R_0402_1005Metric"
			(at 154.305 84.455 0)
			(effects
				(font
					(size 1.27 1.27)
					(thickness 0.15)
				)
				(justify left bottom)
				(hide yes)
			)
		)
		(property "Datasheet" "https://www.bourns.com/docs/product-datasheets/cr.pdf"
			(at 154.305 86.995 0)
			(effects
				(font
					(size 1.27 1.27)
					(thickness 0.15)
				)
				(justify left bottom)
				(hide yes)
			)
		)
		(property "Description" ""
			(at 133.985 69.215 0)
			(effects
				(font
					(size 1.27 1.27)
				)
			)
		)
		(property "Manufacturer" "Bourns"
			(at 154.305 92.075 0)
			(effects
				(font
					(size 1.27 1.27)
					(thickness 0.15)
				)
				(justify left bottom)
				(hide yes)
			)
		)
		(property "MPN" "CR0402-FX-22R0GLF"
			(at 154.305 89.535 0)
			(effects
				(font
					(size 1.27 1.27)
					(thickness 0.15)
				)
				(justify left bottom)
				(hide yes)
			)
		)
		(property "Val" "22R"
			(at 130.175 69.215 0)
			(effects
				(font
					(size 1.27 1.27)
					(thickness 0.15)
				)
				(justify left bottom)
			)
		)
		(property "License" "Apache-2.0"
			(at 154.305 94.615 0)
			(effects
				(font
					(size 1.27 1.27)
					(thickness 0.15)
				)
				(justify left bottom)
				(hide yes)
			)
		)
		(property "Author" "Antmicro"
			(at 154.305 97.155 0)
			(effects
				(font
					(size 1.27 1.27)
					(thickness 0.15)
				)
				(justify left bottom)
				(hide yes)
			)
		)
		(property "Tolerance" "1%"
			(at 154.305 79.375 0)
			(effects
				(font
					(size 1.27 1.27)
				)
				(justify left bottom)
				(hide yes)
			)
		)
		(pin "1"
		)
		(pin "2"
		)
		(instances
			(project "lpddr4-test-board"
				(path ""
					(reference "R18")
					(unit 1)
				)
			)
		)
	)
	(symbol
		(lib_id "antmicroResistors0402:R_22R_0402")
		(at 133.985 71.755 0)
		(unit 1)
		(exclude_from_sim no)
		(in_bom yes)
		(on_board yes)
		(dnp no)
		(property "Reference" "R19"
			(at 139.065 71.755 0)
			(effects
				(font
					(size 1.27 1.27)
					(thickness 0.15)
				)
				(justify left bottom)
			)
		)
		(property "Value" "R_22R_0402"
			(at 154.305 84.455 0)
			(effects
				(font
					(size 1.27 1.27)
					(thickness 0.15)
				)
				(justify left bottom)
				(hide yes)
			)
		)
		(property "Footprint" "antmicro-footprints:R_0402_1005Metric"
			(at 154.305 86.995 0)
			(effects
				(font
					(size 1.27 1.27)
					(thickness 0.15)
				)
				(justify left bottom)
				(hide yes)
			)
		)
		(property "Datasheet" "https://www.bourns.com/docs/product-datasheets/cr.pdf"
			(at 154.305 89.535 0)
			(effects
				(font
					(size 1.27 1.27)
					(thickness 0.15)
				)
				(justify left bottom)
				(hide yes)
			)
		)
		(property "Description" ""
			(at 133.985 71.755 0)
			(effects
				(font
					(size 1.27 1.27)
				)
			)
		)
		(property "Manufacturer" "Bourns"
			(at 154.305 94.615 0)
			(effects
				(font
					(size 1.27 1.27)
					(thickness 0.15)
				)
				(justify left bottom)
				(hide yes)
			)
		)
		(property "MPN" "CR0402-FX-22R0GLF"
			(at 154.305 92.075 0)
			(effects
				(font
					(size 1.27 1.27)
					(thickness 0.15)
				)
				(justify left bottom)
				(hide yes)
			)
		)
		(property "Val" "22R"
			(at 130.175 71.755 0)
			(effects
				(font
					(size 1.27 1.27)
					(thickness 0.15)
				)
				(justify left bottom)
			)
		)
		(property "License" "Apache-2.0"
			(at 154.305 97.155 0)
			(effects
				(font
					(size 1.27 1.27)
					(thickness 0.15)
				)
				(justify left bottom)
				(hide yes)
			)
		)
		(property "Author" "Antmicro"
			(at 154.305 99.695 0)
			(effects
				(font
					(size 1.27 1.27)
					(thickness 0.15)
				)
				(justify left bottom)
				(hide yes)
			)
		)
		(property "Tolerance" "1%"
			(at 154.305 81.915 0)
			(effects
				(font
					(size 1.27 1.27)
				)
				(justify left bottom)
				(hide yes)
			)
		)
		(pin "1"
		)
		(pin "2"
		)
		(instances
			(project "lpddr4-test-board"
				(path ""
					(reference "R19")
					(unit 1)
				)
			)
		)
	)
	(symbol
		(lib_id "antmicroResistors0402:R_22R_0402")
		(at 133.985 74.295 0)
		(unit 1)
		(exclude_from_sim no)
		(in_bom yes)
		(on_board yes)
		(dnp no)
		(property "Reference" "R20"
			(at 139.065 74.295 0)
			(effects
				(font
					(size 1.27 1.27)
					(thickness 0.15)
				)
				(justify left bottom)
			)
		)
		(property "Value" "R_22R_0402"
			(at 154.305 86.995 0)
			(effects
				(font
					(size 1.27 1.27)
					(thickness 0.15)
				)
				(justify left bottom)
				(hide yes)
			)
		)
		(property "Footprint" "antmicro-footprints:R_0402_1005Metric"
			(at 154.305 89.535 0)
			(effects
				(font
					(size 1.27 1.27)
					(thickness 0.15)
				)
				(justify left bottom)
				(hide yes)
			)
		)
		(property "Datasheet" "https://www.bourns.com/docs/product-datasheets/cr.pdf"
			(at 154.305 92.075 0)
			(effects
				(font
					(size 1.27 1.27)
					(thickness 0.15)
				)
				(justify left bottom)
				(hide yes)
			)
		)
		(property "Description" ""
			(at 133.985 74.295 0)
			(effects
				(font
					(size 1.27 1.27)
				)
			)
		)
		(property "Manufacturer" "Bourns"
			(at 154.305 97.155 0)
			(effects
				(font
					(size 1.27 1.27)
					(thickness 0.15)
				)
				(justify left bottom)
				(hide yes)
			)
		)
		(property "MPN" "CR0402-FX-22R0GLF"
			(at 154.305 94.615 0)
			(effects
				(font
					(size 1.27 1.27)
					(thickness 0.15)
				)
				(justify left bottom)
				(hide yes)
			)
		)
		(property "Val" "22R"
			(at 130.175 74.295 0)
			(effects
				(font
					(size 1.27 1.27)
					(thickness 0.15)
				)
				(justify left bottom)
			)
		)
		(property "License" "Apache-2.0"
			(at 154.305 99.695 0)
			(effects
				(font
					(size 1.27 1.27)
					(thickness 0.15)
				)
				(justify left bottom)
				(hide yes)
			)
		)
		(property "Author" "Antmicro"
			(at 154.305 102.235 0)
			(effects
				(font
					(size 1.27 1.27)
					(thickness 0.15)
				)
				(justify left bottom)
				(hide yes)
			)
		)
		(property "Tolerance" "1%"
			(at 154.305 84.455 0)
			(effects
				(font
					(size 1.27 1.27)
				)
				(justify left bottom)
				(hide yes)
			)
		)
		(pin "1"
		)
		(pin "2"
		)
		(instances
			(project "lpddr4-test-board"
				(path ""
					(reference "R20")
					(unit 1)
				)
			)
		)
	)
	(symbol
		(lib_id "antmicroPushbuttonSwitches:SW_B3U-1000P_SMD")
		(at 74.295 245.745 270)
		(unit 1)
		(exclude_from_sim no)
		(in_bom yes)
		(on_board yes)
		(dnp no)
		(property "Reference" "USR_BTN3"
			(at 72.39 255.905 0)
			(effects
				(font
					(size 1.27 1.27)
					(thickness 0.15)
				)
				(justify right top)
			)
		)
		(property "Value" "SW_B3U-1000P"
			(at 79.375 259.08 0)
			(effects
				(font
					(size 1.27 1.27)
					(thickness 0.15)
				)
				(justify right top)
			)
		)
		(property "Footprint" "antmicro-footprints:SW_B3U-1000P_SMD"
			(at 66.675 271.145 0)
			(effects
				(font
					(size 1.27 1.27)
					(thickness 0.15)
				)
				(justify left bottom)
				(hide yes)
			)
		)
		(property "Datasheet" "https://omronfs.omron.com/en_US/ecb/products/pdf/en-b3u.pdf"
			(at 64.135 271.145 0)
			(effects
				(font
					(size 1.27 1.27)
					(thickness 0.15)
				)
				(justify left bottom)
				(hide yes)
			)
		)
		(property "Description" ""
			(at 74.295 245.745 0)
			(effects
				(font
					(size 1.27 1.27)
				)
			)
		)
		(property "MPN" "B3U-1000P"
			(at 68.58 245.11 0)
			(effects
				(font
					(size 1.27 1.27)
					(thickness 0.15)
				)
				(justify left bottom)
			)
		)
		(property "Manufacturer" "Omron"
			(at 59.055 271.145 0)
			(effects
				(font
					(size 1.27 1.27)
					(thickness 0.15)
				)
				(justify left bottom)
				(hide yes)
			)
		)
		(property "Author" "Antmicro"
			(at 56.515 271.145 0)
			(effects
				(font
					(size 1.27 1.27)
					(thickness 0.15)
				)
				(justify left bottom)
				(hide yes)
			)
		)
		(property "License" "Apache-2.0"
			(at 53.975 271.145 0)
			(effects
				(font
					(size 1.27 1.27)
					(thickness 0.15)
				)
				(justify left bottom)
				(hide yes)
			)
		)
		(pin "1"
		)
		(pin "2"
		)
		(instances
			(project "lpddr4-test-board"
				(path ""
					(reference "USR_BTN3")
					(unit 1)
				)
			)
		)
	)
	(symbol
		(lib_id "antmicropower:GND")
		(at 74.295 259.08 0)
		(unit 1)
		(exclude_from_sim no)
		(in_bom yes)
		(on_board yes)
		(dnp no)
		(property "Reference" "#PWR029"
			(at 83.185 261.62 0)
			(effects
				(font
					(size 1.27 1.27)
					(thickness 0.15)
				)
				(justify left bottom)
				(hide yes)
			)
		)
		(property "Value" "GND"
			(at 72.39 263.525 0)
			(effects
				(font
					(size 1.27 1.27)
					(thickness 0.15)
				)
				(justify left bottom)
			)
		)
		(property "Footprint" ""
			(at 83.185 266.7 0)
			(effects
				(font
					(size 1.27 1.27)
					(thickness 0.15)
				)
				(justify left bottom)
				(hide yes)
			)
		)
		(property "Datasheet" ""
			(at 83.185 271.78 0)
			(effects
				(font
					(size 1.27 1.27)
					(thickness 0.15)
				)
				(justify left bottom)
				(hide yes)
			)
		)
		(property "Description" ""
			(at 74.295 259.08 0)
			(effects
				(font
					(size 1.27 1.27)
				)
			)
		)
		(property "Author" "Antmicro"
			(at 83.185 266.7 0)
			(effects
				(font
					(size 1.27 1.27)
					(thickness 0.15)
				)
				(justify left bottom)
				(hide yes)
			)
		)
		(property "License" "Apache-2.0"
			(at 83.185 269.24 0)
			(effects
				(font
					(size 1.27 1.27)
					(thickness 0.15)
				)
				(justify left bottom)
				(hide yes)
			)
		)
		(pin "1"
		)
		(instances
			(project "lpddr4-test-board"
				(path ""
					(reference "#PWR029")
					(unit 1)
				)
			)
		)
	)
	(symbol
		(lib_id "antmicroResistors0402:R_4k7_0402")
		(at 74.295 223.52 270)
		(unit 1)
		(exclude_from_sim no)
		(in_bom yes)
		(on_board yes)
		(dnp no)
		(property "Reference" "R11"
			(at 75.565 226.06 90)
			(effects
				(font
					(size 1.27 1.27)
					(thickness 0.15)
				)
				(justify left bottom)
			)
		)
		(property "Value" "R_4k7_0402"
			(at 61.595 243.84 0)
			(effects
				(font
					(size 1.27 1.27)
					(thickness 0.15)
				)
				(justify left bottom)
				(hide yes)
			)
		)
		(property "Footprint" "antmicro-footprints:R_0402_1005Metric"
			(at 59.055 243.84 0)
			(effects
				(font
					(size 1.27 1.27)
					(thickness 0.15)
				)
				(justify left bottom)
				(hide yes)
			)
		)
		(property "Datasheet" "https://www.bourns.com/docs/product-datasheets/cr.pdf"
			(at 56.515 243.84 0)
			(effects
				(font
					(size 1.27 1.27)
					(thickness 0.15)
				)
				(justify left bottom)
				(hide yes)
			)
		)
		(property "Description" ""
			(at 74.295 223.52 0)
			(effects
				(font
					(size 1.27 1.27)
				)
			)
		)
		(property "Manufacturer" "Bourns"
			(at 51.435 243.84 0)
			(effects
				(font
					(size 1.27 1.27)
					(thickness 0.15)
				)
				(justify left bottom)
				(hide yes)
			)
		)
		(property "MPN" "CR0402-FX-4701GLF"
			(at 53.975 243.84 0)
			(effects
				(font
					(size 1.27 1.27)
					(thickness 0.15)
				)
				(justify left bottom)
				(hide yes)
			)
		)
		(property "Val" "4k7"
			(at 75.565 227.965 90)
			(effects
				(font
					(size 1.27 1.27)
					(thickness 0.15)
				)
				(justify left bottom)
			)
		)
		(property "License" "Apache-2.0"
			(at 48.895 243.84 0)
			(effects
				(font
					(size 1.27 1.27)
					(thickness 0.15)
				)
				(justify left bottom)
				(hide yes)
			)
		)
		(property "Author" "Antmicro"
			(at 46.355 243.84 0)
			(effects
				(font
					(size 1.27 1.27)
					(thickness 0.15)
				)
				(justify left bottom)
				(hide yes)
			)
		)
		(property "Tolerance" "1%"
			(at 64.135 243.84 0)
			(effects
				(font
					(size 1.27 1.27)
				)
				(justify left bottom)
				(hide yes)
			)
		)
		(pin "1"
		)
		(pin "2"
		)
		(instances
			(project "lpddr4-test-board"
				(path ""
					(reference "R11")
					(unit 1)
				)
			)
		)
	)
	(symbol
		(lib_id "antmicroResistors0402:R_22R_0402")
		(at 133.985 88.265 0)
		(unit 1)
		(exclude_from_sim no)
		(in_bom yes)
		(on_board yes)
		(dnp no)
		(property "Reference" "R22"
			(at 139.065 88.265 0)
			(effects
				(font
					(size 1.27 1.27)
					(thickness 0.15)
				)
				(justify left bottom)
			)
		)
		(property "Value" "R_22R_0402"
			(at 154.305 100.965 0)
			(effects
				(font
					(size 1.27 1.27)
					(thickness 0.15)
				)
				(justify left bottom)
				(hide yes)
			)
		)
		(property "Footprint" "antmicro-footprints:R_0402_1005Metric"
			(at 154.305 103.505 0)
			(effects
				(font
					(size 1.27 1.27)
					(thickness 0.15)
				)
				(justify left bottom)
				(hide yes)
			)
		)
		(property "Datasheet" "https://www.bourns.com/docs/product-datasheets/cr.pdf"
			(at 154.305 106.045 0)
			(effects
				(font
					(size 1.27 1.27)
					(thickness 0.15)
				)
				(justify left bottom)
				(hide yes)
			)
		)
		(property "Description" ""
			(at 133.985 88.265 0)
			(effects
				(font
					(size 1.27 1.27)
				)
			)
		)
		(property "Manufacturer" "Bourns"
			(at 154.305 111.125 0)
			(effects
				(font
					(size 1.27 1.27)
					(thickness 0.15)
				)
				(justify left bottom)
				(hide yes)
			)
		)
		(property "MPN" "CR0402-FX-22R0GLF"
			(at 154.305 108.585 0)
			(effects
				(font
					(size 1.27 1.27)
					(thickness 0.15)
				)
				(justify left bottom)
				(hide yes)
			)
		)
		(property "Val" "22R"
			(at 130.175 88.265 0)
			(effects
				(font
					(size 1.27 1.27)
					(thickness 0.15)
				)
				(justify left bottom)
			)
		)
		(property "License" "Apache-2.0"
			(at 154.305 113.665 0)
			(effects
				(font
					(size 1.27 1.27)
					(thickness 0.15)
				)
				(justify left bottom)
				(hide yes)
			)
		)
		(property "Author" "Antmicro"
			(at 154.305 116.205 0)
			(effects
				(font
					(size 1.27 1.27)
					(thickness 0.15)
				)
				(justify left bottom)
				(hide yes)
			)
		)
		(property "Tolerance" "1%"
			(at 154.305 98.425 0)
			(effects
				(font
					(size 1.27 1.27)
				)
				(justify left bottom)
				(hide yes)
			)
		)
		(pin "1"
		)
		(pin "2"
		)
		(instances
			(project "lpddr4-test-board"
				(path ""
					(reference "R22")
					(unit 1)
				)
			)
		)
	)
	(symbol
		(lib_id "antmicroResistors0402:R_22R_0402")
		(at 133.985 112.395 0)
		(unit 1)
		(exclude_from_sim no)
		(in_bom yes)
		(on_board yes)
		(dnp no)
		(property "Reference" "R25"
			(at 139.065 112.395 0)
			(effects
				(font
					(size 1.27 1.27)
					(thickness 0.15)
				)
				(justify left bottom)
			)
		)
		(property "Value" "R_22R_0402"
			(at 154.305 125.095 0)
			(effects
				(font
					(size 1.27 1.27)
					(thickness 0.15)
				)
				(justify left bottom)
				(hide yes)
			)
		)
		(property "Footprint" "antmicro-footprints:R_0402_1005Metric"
			(at 154.305 127.635 0)
			(effects
				(font
					(size 1.27 1.27)
					(thickness 0.15)
				)
				(justify left bottom)
				(hide yes)
			)
		)
		(property "Datasheet" "https://www.bourns.com/docs/product-datasheets/cr.pdf"
			(at 154.305 130.175 0)
			(effects
				(font
					(size 1.27 1.27)
					(thickness 0.15)
				)
				(justify left bottom)
				(hide yes)
			)
		)
		(property "Description" ""
			(at 133.985 112.395 0)
			(effects
				(font
					(size 1.27 1.27)
				)
			)
		)
		(property "Manufacturer" "Bourns"
			(at 154.305 135.255 0)
			(effects
				(font
					(size 1.27 1.27)
					(thickness 0.15)
				)
				(justify left bottom)
				(hide yes)
			)
		)
		(property "MPN" "CR0402-FX-22R0GLF"
			(at 154.305 132.715 0)
			(effects
				(font
					(size 1.27 1.27)
					(thickness 0.15)
				)
				(justify left bottom)
				(hide yes)
			)
		)
		(property "Val" "22R"
			(at 130.175 112.395 0)
			(effects
				(font
					(size 1.27 1.27)
					(thickness 0.15)
				)
				(justify left bottom)
			)
		)
		(property "License" "Apache-2.0"
			(at 154.305 137.795 0)
			(effects
				(font
					(size 1.27 1.27)
					(thickness 0.15)
				)
				(justify left bottom)
				(hide yes)
			)
		)
		(property "Author" "Antmicro"
			(at 154.305 140.335 0)
			(effects
				(font
					(size 1.27 1.27)
					(thickness 0.15)
				)
				(justify left bottom)
				(hide yes)
			)
		)
		(property "Tolerance" "1%"
			(at 154.305 122.555 0)
			(effects
				(font
					(size 1.27 1.27)
				)
				(justify left bottom)
				(hide yes)
			)
		)
		(pin "1"
		)
		(pin "2"
		)
		(instances
			(project "lpddr4-test-board"
				(path ""
					(reference "R25")
					(unit 1)
				)
			)
		)
	)
	(symbol
		(lib_id "antmicroResistors0402:R_22R_0402")
		(at 133.985 90.805 0)
		(unit 1)
		(exclude_from_sim no)
		(in_bom yes)
		(on_board yes)
		(dnp no)
		(property "Reference" "R23"
			(at 139.065 90.805 0)
			(effects
				(font
					(size 1.27 1.27)
					(thickness 0.15)
				)
				(justify left bottom)
			)
		)
		(property "Value" "R_22R_0402"
			(at 154.305 103.505 0)
			(effects
				(font
					(size 1.27 1.27)
					(thickness 0.15)
				)
				(justify left bottom)
				(hide yes)
			)
		)
		(property "Footprint" "antmicro-footprints:R_0402_1005Metric"
			(at 154.305 106.045 0)
			(effects
				(font
					(size 1.27 1.27)
					(thickness 0.15)
				)
				(justify left bottom)
				(hide yes)
			)
		)
		(property "Datasheet" "https://www.bourns.com/docs/product-datasheets/cr.pdf"
			(at 154.305 108.585 0)
			(effects
				(font
					(size 1.27 1.27)
					(thickness 0.15)
				)
				(justify left bottom)
				(hide yes)
			)
		)
		(property "Description" ""
			(at 133.985 90.805 0)
			(effects
				(font
					(size 1.27 1.27)
				)
			)
		)
		(property "Manufacturer" "Bourns"
			(at 154.305 113.665 0)
			(effects
				(font
					(size 1.27 1.27)
					(thickness 0.15)
				)
				(justify left bottom)
				(hide yes)
			)
		)
		(property "MPN" "CR0402-FX-22R0GLF"
			(at 154.305 111.125 0)
			(effects
				(font
					(size 1.27 1.27)
					(thickness 0.15)
				)
				(justify left bottom)
				(hide yes)
			)
		)
		(property "Val" "22R"
			(at 130.175 90.805 0)
			(effects
				(font
					(size 1.27 1.27)
					(thickness 0.15)
				)
				(justify left bottom)
			)
		)
		(property "License" "Apache-2.0"
			(at 154.305 116.205 0)
			(effects
				(font
					(size 1.27 1.27)
					(thickness 0.15)
				)
				(justify left bottom)
				(hide yes)
			)
		)
		(property "Author" "Antmicro"
			(at 154.305 118.745 0)
			(effects
				(font
					(size 1.27 1.27)
					(thickness 0.15)
				)
				(justify left bottom)
				(hide yes)
			)
		)
		(property "Tolerance" "1%"
			(at 154.305 100.965 0)
			(effects
				(font
					(size 1.27 1.27)
				)
				(justify left bottom)
				(hide yes)
			)
		)
		(pin "1"
		)
		(pin "2"
		)
		(instances
			(project "lpddr4-test-board"
				(path ""
					(reference "R23")
					(unit 1)
				)
			)
		)
	)
	(symbol
		(lib_id "antmicroResistors0402:R_22R_0402")
		(at 133.985 109.855 0)
		(unit 1)
		(exclude_from_sim no)
		(in_bom yes)
		(on_board yes)
		(dnp no)
		(property "Reference" "R24"
			(at 139.065 109.855 0)
			(effects
				(font
					(size 1.27 1.27)
					(thickness 0.15)
				)
				(justify left bottom)
			)
		)
		(property "Value" "R_22R_0402"
			(at 154.305 122.555 0)
			(effects
				(font
					(size 1.27 1.27)
					(thickness 0.15)
				)
				(justify left bottom)
				(hide yes)
			)
		)
		(property "Footprint" "antmicro-footprints:R_0402_1005Metric"
			(at 154.305 125.095 0)
			(effects
				(font
					(size 1.27 1.27)
					(thickness 0.15)
				)
				(justify left bottom)
				(hide yes)
			)
		)
		(property "Datasheet" "https://www.bourns.com/docs/product-datasheets/cr.pdf"
			(at 154.305 127.635 0)
			(effects
				(font
					(size 1.27 1.27)
					(thickness 0.15)
				)
				(justify left bottom)
				(hide yes)
			)
		)
		(property "Description" ""
			(at 133.985 109.855 0)
			(effects
				(font
					(size 1.27 1.27)
				)
			)
		)
		(property "Manufacturer" "Bourns"
			(at 154.305 132.715 0)
			(effects
				(font
					(size 1.27 1.27)
					(thickness 0.15)
				)
				(justify left bottom)
				(hide yes)
			)
		)
		(property "MPN" "CR0402-FX-22R0GLF"
			(at 154.305 130.175 0)
			(effects
				(font
					(size 1.27 1.27)
					(thickness 0.15)
				)
				(justify left bottom)
				(hide yes)
			)
		)
		(property "Val" "22R"
			(at 130.175 109.855 0)
			(effects
				(font
					(size 1.27 1.27)
					(thickness 0.15)
				)
				(justify left bottom)
			)
		)
		(property "License" "Apache-2.0"
			(at 154.305 135.255 0)
			(effects
				(font
					(size 1.27 1.27)
					(thickness 0.15)
				)
				(justify left bottom)
				(hide yes)
			)
		)
		(property "Author" "Antmicro"
			(at 154.305 137.795 0)
			(effects
				(font
					(size 1.27 1.27)
					(thickness 0.15)
				)
				(justify left bottom)
				(hide yes)
			)
		)
		(property "Tolerance" "1%"
			(at 154.305 120.015 0)
			(effects
				(font
					(size 1.27 1.27)
				)
				(justify left bottom)
				(hide yes)
			)
		)
		(pin "1"
		)
		(pin "2"
		)
		(instances
			(project "lpddr4-test-board"
				(path ""
					(reference "R24")
					(unit 1)
				)
			)
		)
	)
	(symbol
		(lib_id "antmicropower:GND")
		(at 195.58 223.52 0)
		(unit 1)
		(exclude_from_sim no)
		(in_bom yes)
		(on_board yes)
		(dnp no)
		(property "Reference" "#PWR032"
			(at 204.47 226.06 0)
			(effects
				(font
					(size 1.27 1.27)
					(thickness 0.15)
				)
				(justify left bottom)
				(hide yes)
			)
		)
		(property "Value" "GND"
			(at 193.675 227.965 0)
			(effects
				(font
					(size 1.27 1.27)
					(thickness 0.15)
				)
				(justify left bottom)
			)
		)
		(property "Footprint" ""
			(at 204.47 231.14 0)
			(effects
				(font
					(size 1.27 1.27)
					(thickness 0.15)
				)
				(justify left bottom)
				(hide yes)
			)
		)
		(property "Datasheet" ""
			(at 204.47 236.22 0)
			(effects
				(font
					(size 1.27 1.27)
					(thickness 0.15)
				)
				(justify left bottom)
				(hide yes)
			)
		)
		(property "Description" ""
			(at 195.58 223.52 0)
			(effects
				(font
					(size 1.27 1.27)
				)
			)
		)
		(property "Author" "Antmicro"
			(at 204.47 231.14 0)
			(effects
				(font
					(size 1.27 1.27)
					(thickness 0.15)
				)
				(justify left bottom)
				(hide yes)
			)
		)
		(property "License" "Apache-2.0"
			(at 204.47 233.68 0)
			(effects
				(font
					(size 1.27 1.27)
					(thickness 0.15)
				)
				(justify left bottom)
				(hide yes)
			)
		)
		(pin "1"
		)
		(instances
			(project "lpddr4-test-board"
				(path ""
					(reference "#PWR032")
					(unit 1)
				)
			)
		)
	)
	(symbol
		(lib_id "antmicroResistors0402:R_330R_0402")
		(at 170.815 220.98 0)
		(unit 1)
		(exclude_from_sim no)
		(in_bom yes)
		(on_board yes)
		(dnp no)
		(property "Reference" "R26"
			(at 175.895 220.98 0)
			(effects
				(font
					(size 1.27 1.27)
					(thickness 0.15)
				)
				(justify left bottom)
			)
		)
		(property "Value" "R_330R_0402"
			(at 191.135 233.68 0)
			(effects
				(font
					(size 1.27 1.27)
					(thickness 0.15)
				)
				(justify left bottom)
				(hide yes)
			)
		)
		(property "Footprint" "antmicro-footprints:R_0402_1005Metric"
			(at 191.135 236.22 0)
			(effects
				(font
					(size 1.27 1.27)
					(thickness 0.15)
				)
				(justify left bottom)
				(hide yes)
			)
		)
		(property "Datasheet" "https://www.bourns.com/docs/product-datasheets/cr.pdf"
			(at 191.135 238.76 0)
			(effects
				(font
					(size 1.27 1.27)
					(thickness 0.15)
				)
				(justify left bottom)
				(hide yes)
			)
		)
		(property "Description" ""
			(at 170.815 220.98 0)
			(effects
				(font
					(size 1.27 1.27)
				)
			)
		)
		(property "Manufacturer" "Bourns"
			(at 191.135 243.84 0)
			(effects
				(font
					(size 1.27 1.27)
					(thickness 0.15)
				)
				(justify left bottom)
				(hide yes)
			)
		)
		(property "MPN" "CR0402-FX-3300GLF"
			(at 191.135 241.3 0)
			(effects
				(font
					(size 1.27 1.27)
					(thickness 0.15)
				)
				(justify left bottom)
				(hide yes)
			)
		)
		(property "Val" "330R"
			(at 165.735 220.98 0)
			(effects
				(font
					(size 1.27 1.27)
					(thickness 0.15)
				)
				(justify left bottom)
			)
		)
		(property "License" "Apache-2.0"
			(at 191.135 246.38 0)
			(effects
				(font
					(size 1.27 1.27)
					(thickness 0.15)
				)
				(justify left bottom)
				(hide yes)
			)
		)
		(property "Author" "Antmicro"
			(at 191.135 248.92 0)
			(effects
				(font
					(size 1.27 1.27)
					(thickness 0.15)
				)
				(justify left bottom)
				(hide yes)
			)
		)
		(property "Tolerance" "1%"
			(at 191.135 231.14 0)
			(effects
				(font
					(size 1.27 1.27)
				)
				(justify left bottom)
				(hide yes)
			)
		)
		(pin "1"
		)
		(pin "2"
		)
		(instances
			(project "lpddr4-test-board"
				(path ""
					(reference "R26")
					(unit 1)
				)
			)
		)
	)
	(symbol
		(lib_id "antmicroLEDIndicationDiscrete:LED_G_0603_KP-1608CGCK")
		(at 156.21 220.98 0)
		(unit 1)
		(exclude_from_sim no)
		(in_bom yes)
		(on_board yes)
		(dnp no)
		(property "Reference" "D1"
			(at 158.75 215.9 0)
			(effects
				(font
					(size 1.27 1.27)
					(thickness 0.15)
				)
				(justify left bottom)
			)
		)
		(property "Value" "LED_G_0603_KP-1608CGCK"
			(at 146.05 218.44 0)
			(effects
				(font
					(size 1.27 1.27)
					(thickness 0.15)
				)
				(justify left bottom)
			)
		)
		(property "Footprint" "antmicro-footprints:LED_0603_1608Metric_G"
			(at 179.07 231.14 0)
			(effects
				(font
					(size 1.27 1.27)
					(thickness 0.15)
				)
				(justify left bottom)
				(hide yes)
			)
		)
		(property "Datasheet" "http://www.farnell.com/datasheets/2045956.pdf"
			(at 179.07 233.68 0)
			(effects
				(font
					(size 1.27 1.27)
					(thickness 0.15)
				)
				(justify left bottom)
				(hide yes)
			)
		)
		(property "Description" ""
			(at 156.21 220.98 0)
			(effects
				(font
					(size 1.27 1.27)
				)
			)
		)
		(property "MPN" "KP-1608CGCK"
			(at 179.07 236.22 0)
			(effects
				(font
					(size 1.27 1.27)
					(thickness 0.15)
				)
				(justify left bottom)
				(hide yes)
			)
		)
		(property "Manufacturer" "Kingbright"
			(at 179.07 238.76 0)
			(effects
				(font
					(size 1.27 1.27)
					(thickness 0.15)
				)
				(justify left bottom)
				(hide yes)
			)
		)
		(property "Author" "Antmicro"
			(at 179.07 241.3 0)
			(effects
				(font
					(size 1.27 1.27)
					(thickness 0.15)
				)
				(justify left bottom)
				(hide yes)
			)
		)
		(property "License" "Apache-2.0"
			(at 179.07 243.84 0)
			(effects
				(font
					(size 1.27 1.27)
					(thickness 0.15)
				)
				(justify left bottom)
				(hide yes)
			)
		)
		(pin "1"
		)
		(pin "2"
		)
		(instances
			(project "lpddr4-test-board"
				(path ""
					(reference "D1")
					(unit 1)
				)
			)
		)
	)
	(symbol
		(lib_id "antmicroFerriteBeadsandChips:FB_600Z_0.5A_Murata-BLM18AG_0603")
		(at 31.75 104.775 0)
		(unit 1)
		(exclude_from_sim no)
		(in_bom yes)
		(on_board yes)
		(dnp no)
		(property "Reference" "FB2"
			(at 33.02 100.965 0)
			(effects
				(font
					(size 1.27 1.27)
					(thickness 0.15)
				)
				(justify left bottom)
			)
		)
		(property "Value" "FB_600Z_0.5A_0603"
			(at 46.99 109.855 0)
			(effects
				(font
					(size 1.27 1.27)
					(thickness 0.15)
				)
				(justify left bottom)
				(hide yes)
			)
		)
		(property "Footprint" "antmicro-footprints:FB_0603_1608Metric"
			(at 46.99 112.395 0)
			(effects
				(font
					(size 1.27 1.27)
					(thickness 0.15)
				)
				(justify left bottom)
				(hide yes)
			)
		)
		(property "Datasheet" "https://www.murata.com/en-us/products/productdata/8796738650142/ENFA0003.pdf"
			(at 46.99 114.935 0)
			(effects
				(font
					(size 1.27 1.27)
					(thickness 0.15)
				)
				(justify left bottom)
				(hide yes)
			)
		)
		(property "Description" ""
			(at 31.75 104.775 0)
			(effects
				(font
					(size 1.27 1.27)
				)
			)
		)
		(property "MPN" "BLM18AG601SN1D"
			(at 26.67 102.87 0)
			(effects
				(font
					(size 1.27 1.27)
					(thickness 0.15)
				)
				(justify left bottom)
			)
		)
		(property "Manufacturer" "Murata"
			(at 46.99 120.015 0)
			(effects
				(font
					(size 1.27 1.27)
					(thickness 0.15)
				)
				(justify left bottom)
				(hide yes)
			)
		)
		(property "Author" "Antmicro"
			(at 46.99 122.555 0)
			(effects
				(font
					(size 1.27 1.27)
					(thickness 0.15)
				)
				(justify left bottom)
				(hide yes)
			)
		)
		(property "License" "Apache-2.0"
			(at 46.99 125.095 0)
			(effects
				(font
					(size 1.27 1.27)
					(thickness 0.15)
				)
				(justify left bottom)
				(hide yes)
			)
		)
		(pin "1"
		)
		(pin "2"
		)
		(instances
			(project "lpddr4-test-board"
				(path ""
					(reference "FB2")
					(unit 1)
				)
			)
		)
	)
	(symbol
		(lib_id "antmicroFerriteBeadsandChips:FB_600Z_0.5A_Murata-BLM18AG_0603")
		(at 31.75 83.82 0)
		(unit 1)
		(exclude_from_sim no)
		(in_bom yes)
		(on_board yes)
		(dnp no)
		(property "Reference" "FB1"
			(at 33.02 80.01 0)
			(effects
				(font
					(size 1.27 1.27)
					(thickness 0.15)
				)
				(justify left bottom)
			)
		)
		(property "Value" "FB_600Z_0.5A_0603"
			(at 46.99 88.9 0)
			(effects
				(font
					(size 1.27 1.27)
					(thickness 0.15)
				)
				(justify left bottom)
				(hide yes)
			)
		)
		(property "Footprint" "antmicro-footprints:FB_0603_1608Metric"
			(at 46.99 91.44 0)
			(effects
				(font
					(size 1.27 1.27)
					(thickness 0.15)
				)
				(justify left bottom)
				(hide yes)
			)
		)
		(property "Datasheet" "https://www.murata.com/en-us/products/productdata/8796738650142/ENFA0003.pdf"
			(at 46.99 93.98 0)
			(effects
				(font
					(size 1.27 1.27)
					(thickness 0.15)
				)
				(justify left bottom)
				(hide yes)
			)
		)
		(property "Description" ""
			(at 31.75 83.82 0)
			(effects
				(font
					(size 1.27 1.27)
				)
			)
		)
		(property "MPN" "BLM18AG601SN1D"
			(at 26.67 81.915 0)
			(effects
				(font
					(size 1.27 1.27)
					(thickness 0.15)
				)
				(justify left bottom)
			)
		)
		(property "Manufacturer" "Murata"
			(at 46.99 99.06 0)
			(effects
				(font
					(size 1.27 1.27)
					(thickness 0.15)
				)
				(justify left bottom)
				(hide yes)
			)
		)
		(property "Author" "Antmicro"
			(at 46.99 101.6 0)
			(effects
				(font
					(size 1.27 1.27)
					(thickness 0.15)
				)
				(justify left bottom)
				(hide yes)
			)
		)
		(property "License" "Apache-2.0"
			(at 46.99 104.14 0)
			(effects
				(font
					(size 1.27 1.27)
					(thickness 0.15)
				)
				(justify left bottom)
				(hide yes)
			)
		)
		(pin "1"
		)
		(pin "2"
		)
		(instances
			(project "lpddr4-test-board"
				(path ""
					(reference "FB1")
					(unit 1)
				)
			)
		)
	)
	(symbol
		(lib_id "antmicroCapacitorsmisc:C_100n_6V3_0402")
		(at 46.355 111.125 90)
		(unit 1)
		(exclude_from_sim no)
		(in_bom yes)
		(on_board yes)
		(dnp no)
		(property "Reference" "C11"
			(at 46.99 107.95 90)
			(effects
				(font
					(size 1.27 1.27)
					(thickness 0.15)
				)
				(justify right top)
			)
		)
		(property "Value" "C_100n_6V3_0402"
			(at 56.515 90.805 0)
			(effects
				(font
					(size 1.27 1.27)
					(thickness 0.15)
				)
				(justify left bottom)
				(hide yes)
			)
		)
		(property "Footprint" "antmicro-footprints:C_0402_1005Metric"
			(at 59.055 90.805 0)
			(effects
				(font
					(size 1.27 1.27)
					(thickness 0.15)
				)
				(justify left bottom)
				(hide yes)
			)
		)
		(property "Datasheet" " "
			(at 61.595 90.805 0)
			(effects
				(font
					(size 1.27 1.27)
					(thickness 0.15)
				)
				(justify left bottom)
				(hide yes)
			)
		)
		(property "Description" ""
			(at 46.355 111.125 0)
			(effects
				(font
					(size 1.27 1.27)
				)
			)
		)
		(property "Manufacturer" "Walsin"
			(at 66.675 90.805 0)
			(effects
				(font
					(size 1.27 1.27)
					(thickness 0.15)
				)
				(justify left bottom)
				(hide yes)
			)
		)
		(property "MPN" "0402X104K6R3CT"
			(at 64.135 90.805 0)
			(effects
				(font
					(size 1.27 1.27)
					(thickness 0.15)
				)
				(justify left bottom)
				(hide yes)
			)
		)
		(property "Val" "100n"
			(at 46.99 111.76 90)
			(effects
				(font
					(size 1.27 1.27)
					(thickness 0.15)
				)
				(justify right top)
			)
		)
		(property "License" "Apache-2.0"
			(at 69.215 90.805 0)
			(effects
				(font
					(size 1.27 1.27)
					(thickness 0.15)
				)
				(justify left bottom)
				(hide yes)
			)
		)
		(property "Author" "Antmicro"
			(at 71.755 90.805 0)
			(effects
				(font
					(size 1.27 1.27)
					(thickness 0.15)
				)
				(justify left bottom)
				(hide yes)
			)
		)
		(property "Voltage" ""
			(at 74.295 90.805 0)
			(effects
				(font
					(size 1.27 1.27)
				)
				(justify left bottom)
				(hide yes)
			)
		)
		(property "Dielectric" ""
			(at 76.835 90.805 0)
			(effects
				(font
					(size 1.27 1.27)
				)
				(justify left bottom)
				(hide yes)
			)
		)
		(pin "1"
		)
		(pin "2"
		)
		(instances
			(project "lpddr4-test-board"
				(path ""
					(reference "C11")
					(unit 1)
				)
			)
		)
	)
	(symbol
		(lib_id "antmicroCapacitors0402:C_4u7_0402")
		(at 39.37 111.125 90)
		(unit 1)
		(exclude_from_sim no)
		(in_bom yes)
		(on_board yes)
		(dnp no)
		(property "Reference" "C18"
			(at 40.005 107.95 90)
			(effects
				(font
					(size 1.27 1.27)
					(thickness 0.15)
				)
				(justify right top)
			)
		)
		(property "Value" "C_4u7_0402"
			(at 49.53 90.805 0)
			(effects
				(font
					(size 1.27 1.27)
					(thickness 0.15)
				)
				(justify left bottom)
				(hide yes)
			)
		)
		(property "Footprint" "antmicro-footprints:C_0402_1005Metric"
			(at 52.07 90.805 0)
			(effects
				(font
					(size 1.27 1.27)
					(thickness 0.15)
				)
				(justify left bottom)
				(hide yes)
			)
		)
		(property "Datasheet" " "
			(at 54.61 90.805 0)
			(effects
				(font
					(size 1.27 1.27)
					(thickness 0.15)
				)
				(justify left bottom)
				(hide yes)
			)
		)
		(property "Description" ""
			(at 39.37 111.125 0)
			(effects
				(font
					(size 1.27 1.27)
				)
			)
		)
		(property "Manufacturer" "Murata"
			(at 59.69 90.805 0)
			(effects
				(font
					(size 1.27 1.27)
					(thickness 0.15)
				)
				(justify left bottom)
				(hide yes)
			)
		)
		(property "MPN" "GRM155R61A475MEAAD"
			(at 57.15 90.805 0)
			(effects
				(font
					(size 1.27 1.27)
					(thickness 0.15)
				)
				(justify left bottom)
				(hide yes)
			)
		)
		(property "Val" "4u7"
			(at 40.005 111.76 90)
			(effects
				(font
					(size 1.27 1.27)
					(thickness 0.15)
				)
				(justify right top)
			)
		)
		(property "License" "Apache-2.0"
			(at 62.23 90.805 0)
			(effects
				(font
					(size 1.27 1.27)
					(thickness 0.15)
				)
				(justify left bottom)
				(hide yes)
			)
		)
		(property "Author" "Antmicro"
			(at 64.77 90.805 0)
			(effects
				(font
					(size 1.27 1.27)
					(thickness 0.15)
				)
				(justify left bottom)
				(hide yes)
			)
		)
		(property "Voltage" ""
			(at 67.31 90.805 0)
			(effects
				(font
					(size 1.27 1.27)
				)
				(justify left bottom)
				(hide yes)
			)
		)
		(property "Dielectric" ""
			(at 69.85 90.805 0)
			(effects
				(font
					(size 1.27 1.27)
				)
				(justify left bottom)
				(hide yes)
			)
		)
		(pin "1"
		)
		(pin "2"
		)
		(instances
			(project "lpddr4-test-board"
				(path ""
					(reference "C18")
					(unit 1)
				)
			)
		)
	)
	(symbol
		(lib_id "antmicroCapacitorsmisc:C_100n_6V3_0402")
		(at 46.355 90.17 90)
		(unit 1)
		(exclude_from_sim no)
		(in_bom yes)
		(on_board yes)
		(dnp no)
		(property "Reference" "C8"
			(at 46.99 86.995 90)
			(effects
				(font
					(size 1.27 1.27)
					(thickness 0.15)
				)
				(justify right top)
			)
		)
		(property "Value" "C_100n_6V3_0402"
			(at 56.515 69.85 0)
			(effects
				(font
					(size 1.27 1.27)
					(thickness 0.15)
				)
				(justify left bottom)
				(hide yes)
			)
		)
		(property "Footprint" "antmicro-footprints:C_0402_1005Metric"
			(at 59.055 69.85 0)
			(effects
				(font
					(size 1.27 1.27)
					(thickness 0.15)
				)
				(justify left bottom)
				(hide yes)
			)
		)
		(property "Datasheet" " "
			(at 61.595 69.85 0)
			(effects
				(font
					(size 1.27 1.27)
					(thickness 0.15)
				)
				(justify left bottom)
				(hide yes)
			)
		)
		(property "Description" ""
			(at 46.355 90.17 0)
			(effects
				(font
					(size 1.27 1.27)
				)
			)
		)
		(property "Manufacturer" "Walsin"
			(at 66.675 69.85 0)
			(effects
				(font
					(size 1.27 1.27)
					(thickness 0.15)
				)
				(justify left bottom)
				(hide yes)
			)
		)
		(property "MPN" "0402X104K6R3CT"
			(at 64.135 69.85 0)
			(effects
				(font
					(size 1.27 1.27)
					(thickness 0.15)
				)
				(justify left bottom)
				(hide yes)
			)
		)
		(property "Val" "100n"
			(at 46.99 90.805 90)
			(effects
				(font
					(size 1.27 1.27)
					(thickness 0.15)
				)
				(justify right top)
			)
		)
		(property "License" "Apache-2.0"
			(at 69.215 69.85 0)
			(effects
				(font
					(size 1.27 1.27)
					(thickness 0.15)
				)
				(justify left bottom)
				(hide yes)
			)
		)
		(property "Author" "Antmicro"
			(at 71.755 69.85 0)
			(effects
				(font
					(size 1.27 1.27)
					(thickness 0.15)
				)
				(justify left bottom)
				(hide yes)
			)
		)
		(property "Voltage" ""
			(at 74.295 69.85 0)
			(effects
				(font
					(size 1.27 1.27)
				)
				(justify left bottom)
				(hide yes)
			)
		)
		(property "Dielectric" ""
			(at 76.835 69.85 0)
			(effects
				(font
					(size 1.27 1.27)
				)
				(justify left bottom)
				(hide yes)
			)
		)
		(pin "1"
		)
		(pin "2"
		)
		(instances
			(project "lpddr4-test-board"
				(path ""
					(reference "C8")
					(unit 1)
				)
			)
		)
	)
	(symbol
		(lib_id "antmicroCapacitors0402:C_4u7_0402")
		(at 39.37 90.17 90)
		(unit 1)
		(exclude_from_sim no)
		(in_bom yes)
		(on_board yes)
		(dnp no)
		(property "Reference" "C14"
			(at 40.005 86.995 90)
			(effects
				(font
					(size 1.27 1.27)
					(thickness 0.15)
				)
				(justify right top)
			)
		)
		(property "Value" "C_4u7_0402"
			(at 49.53 69.85 0)
			(effects
				(font
					(size 1.27 1.27)
					(thickness 0.15)
				)
				(justify left bottom)
				(hide yes)
			)
		)
		(property "Footprint" "antmicro-footprints:C_0402_1005Metric"
			(at 52.07 69.85 0)
			(effects
				(font
					(size 1.27 1.27)
					(thickness 0.15)
				)
				(justify left bottom)
				(hide yes)
			)
		)
		(property "Datasheet" " "
			(at 54.61 69.85 0)
			(effects
				(font
					(size 1.27 1.27)
					(thickness 0.15)
				)
				(justify left bottom)
				(hide yes)
			)
		)
		(property "Description" ""
			(at 39.37 90.17 0)
			(effects
				(font
					(size 1.27 1.27)
				)
			)
		)
		(property "Manufacturer" "Murata"
			(at 59.69 69.85 0)
			(effects
				(font
					(size 1.27 1.27)
					(thickness 0.15)
				)
				(justify left bottom)
				(hide yes)
			)
		)
		(property "MPN" "GRM155R61A475MEAAD"
			(at 57.15 69.85 0)
			(effects
				(font
					(size 1.27 1.27)
					(thickness 0.15)
				)
				(justify left bottom)
				(hide yes)
			)
		)
		(property "Val" "4u7"
			(at 40.005 90.805 90)
			(effects
				(font
					(size 1.27 1.27)
					(thickness 0.15)
				)
				(justify right top)
			)
		)
		(property "License" "Apache-2.0"
			(at 62.23 69.85 0)
			(effects
				(font
					(size 1.27 1.27)
					(thickness 0.15)
				)
				(justify left bottom)
				(hide yes)
			)
		)
		(property "Author" "Antmicro"
			(at 64.77 69.85 0)
			(effects
				(font
					(size 1.27 1.27)
					(thickness 0.15)
				)
				(justify left bottom)
				(hide yes)
			)
		)
		(property "Voltage" ""
			(at 67.31 69.85 0)
			(effects
				(font
					(size 1.27 1.27)
				)
				(justify left bottom)
				(hide yes)
			)
		)
		(property "Dielectric" ""
			(at 69.85 69.85 0)
			(effects
				(font
					(size 1.27 1.27)
				)
				(justify left bottom)
				(hide yes)
			)
		)
		(pin "1"
		)
		(pin "2"
		)
		(instances
			(project "lpddr4-test-board"
				(path ""
					(reference "C14")
					(unit 1)
				)
			)
		)
	)
	(symbol
		(lib_id "antmicroResistors0402:R_12k_0402")
		(at 83.185 125.095 270)
		(unit 1)
		(exclude_from_sim no)
		(in_bom yes)
		(on_board yes)
		(dnp no)
		(property "Reference" "R7"
			(at 84.455 127.635 90)
			(effects
				(font
					(size 1.27 1.27)
					(thickness 0.15)
				)
				(justify left bottom)
			)
		)
		(property "Value" "R_12k_0402"
			(at 70.485 145.415 0)
			(effects
				(font
					(size 1.27 1.27)
					(thickness 0.15)
				)
				(justify left bottom)
				(hide yes)
			)
		)
		(property "Footprint" "antmicro-footprints:R_0402_1005Metric"
			(at 67.945 145.415 0)
			(effects
				(font
					(size 1.27 1.27)
					(thickness 0.15)
				)
				(justify left bottom)
				(hide yes)
			)
		)
		(property "Datasheet" "https://www.bourns.com/docs/product-datasheets/cr.pdf"
			(at 65.405 145.415 0)
			(effects
				(font
					(size 1.27 1.27)
					(thickness 0.15)
				)
				(justify left bottom)
				(hide yes)
			)
		)
		(property "Description" ""
			(at 83.185 125.095 0)
			(effects
				(font
					(size 1.27 1.27)
				)
			)
		)
		(property "Manufacturer" "Bourns"
			(at 60.325 145.415 0)
			(effects
				(font
					(size 1.27 1.27)
					(thickness 0.15)
				)
				(justify left bottom)
				(hide yes)
			)
		)
		(property "MPN" "CR0402-FX-1202GLF"
			(at 62.865 145.415 0)
			(effects
				(font
					(size 1.27 1.27)
					(thickness 0.15)
				)
				(justify left bottom)
				(hide yes)
			)
		)
		(property "Val" "12k"
			(at 84.455 129.54 90)
			(effects
				(font
					(size 1.27 1.27)
					(thickness 0.15)
				)
				(justify left bottom)
			)
		)
		(property "License" "Apache-2.0"
			(at 57.785 145.415 0)
			(effects
				(font
					(size 1.27 1.27)
					(thickness 0.15)
				)
				(justify left bottom)
				(hide yes)
			)
		)
		(property "Author" "Antmicro"
			(at 55.245 145.415 0)
			(effects
				(font
					(size 1.27 1.27)
					(thickness 0.15)
				)
				(justify left bottom)
				(hide yes)
			)
		)
		(property "Tolerance" "1%"
			(at 73.025 145.415 0)
			(effects
				(font
					(size 1.27 1.27)
				)
				(justify left bottom)
				(hide yes)
			)
		)
		(pin "1"
		)
		(pin "2"
		)
		(instances
			(project "lpddr4-test-board"
				(path ""
					(reference "R7")
					(unit 1)
				)
			)
		)
	)
	(symbol
		(lib_id "antmicroResistors0402:R_10k_0402")
		(at 79.375 81.915 0)
		(unit 1)
		(exclude_from_sim no)
		(in_bom yes)
		(on_board yes)
		(dnp no)
		(property "Reference" "R8"
			(at 84.455 81.915 0)
			(effects
				(font
					(size 1.27 1.27)
					(thickness 0.15)
				)
				(justify left bottom)
			)
		)
		(property "Value" "R_10k_0402"
			(at 99.695 94.615 0)
			(effects
				(font
					(size 1.27 1.27)
					(thickness 0.15)
				)
				(justify left bottom)
				(hide yes)
			)
		)
		(property "Footprint" "antmicro-footprints:R_0402_1005Metric"
			(at 99.695 97.155 0)
			(effects
				(font
					(size 1.27 1.27)
					(thickness 0.15)
				)
				(justify left bottom)
				(hide yes)
			)
		)
		(property "Datasheet" "https://www.bourns.com/docs/product-datasheets/cr.pdf"
			(at 99.695 99.695 0)
			(effects
				(font
					(size 1.27 1.27)
					(thickness 0.15)
				)
				(justify left bottom)
				(hide yes)
			)
		)
		(property "Description" ""
			(at 79.375 81.915 0)
			(effects
				(font
					(size 1.27 1.27)
				)
			)
		)
		(property "Manufacturer" "Bourns"
			(at 99.695 104.775 0)
			(effects
				(font
					(size 1.27 1.27)
					(thickness 0.15)
				)
				(justify left bottom)
				(hide yes)
			)
		)
		(property "MPN" "CR0402-FX-1002GLF"
			(at 99.695 102.235 0)
			(effects
				(font
					(size 1.27 1.27)
					(thickness 0.15)
				)
				(justify left bottom)
				(hide yes)
			)
		)
		(property "Val" "10k"
			(at 76.2 81.915 0)
			(effects
				(font
					(size 1.27 1.27)
					(thickness 0.15)
				)
				(justify left bottom)
			)
		)
		(property "License" "Apache-2.0"
			(at 99.695 107.315 0)
			(effects
				(font
					(size 1.27 1.27)
					(thickness 0.15)
				)
				(justify left bottom)
				(hide yes)
			)
		)
		(property "Author" "Antmicro"
			(at 99.695 109.855 0)
			(effects
				(font
					(size 1.27 1.27)
					(thickness 0.15)
				)
				(justify left bottom)
				(hide yes)
			)
		)
		(property "Tolerance" "1%"
			(at 99.695 92.075 0)
			(effects
				(font
					(size 1.27 1.27)
				)
				(justify left bottom)
				(hide yes)
			)
		)
		(pin "1"
		)
		(pin "2"
		)
		(instances
			(project "lpddr4-test-board"
				(path ""
					(reference "R8")
					(unit 1)
				)
			)
		)
	)
	(symbol
		(lib_id "antmicroCapacitors0402:C_18p_0402")
		(at 65.405 114.935 90)
		(unit 1)
		(exclude_from_sim no)
		(in_bom yes)
		(on_board yes)
		(dnp no)
		(property "Reference" "C16"
			(at 66.04 111.76 90)
			(effects
				(font
					(size 1.27 1.27)
					(thickness 0.15)
				)
				(justify right top)
			)
		)
		(property "Value" "C_18p_0402"
			(at 75.565 94.615 0)
			(effects
				(font
					(size 1.27 1.27)
					(thickness 0.15)
				)
				(justify left bottom)
				(hide yes)
			)
		)
		(property "Footprint" "antmicro-footprints:C_0402_1005Metric"
			(at 78.105 94.615 0)
			(effects
				(font
					(size 1.27 1.27)
					(thickness 0.15)
				)
				(justify left bottom)
				(hide yes)
			)
		)
		(property "Datasheet" " "
			(at 80.645 94.615 0)
			(effects
				(font
					(size 1.27 1.27)
					(thickness 0.15)
				)
				(justify left bottom)
				(hide yes)
			)
		)
		(property "Description" ""
			(at 65.405 114.935 0)
			(effects
				(font
					(size 1.27 1.27)
				)
			)
		)
		(property "Manufacturer" "Multicomp"
			(at 85.725 94.615 0)
			(effects
				(font
					(size 1.27 1.27)
					(thickness 0.15)
				)
				(justify left bottom)
				(hide yes)
			)
		)
		(property "MPN" "MC0402N180J500CT"
			(at 83.185 94.615 0)
			(effects
				(font
					(size 1.27 1.27)
					(thickness 0.15)
				)
				(justify left bottom)
				(hide yes)
			)
		)
		(property "Val" "18p"
			(at 66.04 115.57 90)
			(effects
				(font
					(size 1.27 1.27)
					(thickness 0.15)
				)
				(justify right top)
			)
		)
		(property "License" "Apache-2.0"
			(at 88.265 94.615 0)
			(effects
				(font
					(size 1.27 1.27)
					(thickness 0.15)
				)
				(justify left bottom)
				(hide yes)
			)
		)
		(property "Author" "Antmicro"
			(at 90.805 94.615 0)
			(effects
				(font
					(size 1.27 1.27)
					(thickness 0.15)
				)
				(justify left bottom)
				(hide yes)
			)
		)
		(property "Voltage" ""
			(at 93.345 94.615 0)
			(effects
				(font
					(size 1.27 1.27)
				)
				(justify left bottom)
				(hide yes)
			)
		)
		(property "Dielectric" ""
			(at 95.885 94.615 0)
			(effects
				(font
					(size 1.27 1.27)
				)
				(justify left bottom)
				(hide yes)
			)
		)
		(pin "1"
		)
		(pin "2"
		)
		(instances
			(project "lpddr4-test-board"
				(path ""
					(reference "C16")
					(unit 1)
				)
			)
		)
	)
	(symbol
		(lib_id "antmicroCapacitors0402:C_18p_0402")
		(at 83.185 114.935 90)
		(unit 1)
		(exclude_from_sim no)
		(in_bom yes)
		(on_board yes)
		(dnp no)
		(property "Reference" "C20"
			(at 83.82 111.76 90)
			(effects
				(font
					(size 1.27 1.27)
					(thickness 0.15)
				)
				(justify right top)
			)
		)
		(property "Value" "C_18p_0402"
			(at 93.345 94.615 0)
			(effects
				(font
					(size 1.27 1.27)
					(thickness 0.15)
				)
				(justify left bottom)
				(hide yes)
			)
		)
		(property "Footprint" "antmicro-footprints:C_0402_1005Metric"
			(at 95.885 94.615 0)
			(effects
				(font
					(size 1.27 1.27)
					(thickness 0.15)
				)
				(justify left bottom)
				(hide yes)
			)
		)
		(property "Datasheet" " "
			(at 98.425 94.615 0)
			(effects
				(font
					(size 1.27 1.27)
					(thickness 0.15)
				)
				(justify left bottom)
				(hide yes)
			)
		)
		(property "Description" ""
			(at 83.185 114.935 0)
			(effects
				(font
					(size 1.27 1.27)
				)
			)
		)
		(property "Manufacturer" "Multicomp"
			(at 103.505 94.615 0)
			(effects
				(font
					(size 1.27 1.27)
					(thickness 0.15)
				)
				(justify left bottom)
				(hide yes)
			)
		)
		(property "MPN" "MC0402N180J500CT"
			(at 100.965 94.615 0)
			(effects
				(font
					(size 1.27 1.27)
					(thickness 0.15)
				)
				(justify left bottom)
				(hide yes)
			)
		)
		(property "Val" "18p"
			(at 83.82 115.57 90)
			(effects
				(font
					(size 1.27 1.27)
					(thickness 0.15)
				)
				(justify right top)
			)
		)
		(property "License" "Apache-2.0"
			(at 106.045 94.615 0)
			(effects
				(font
					(size 1.27 1.27)
					(thickness 0.15)
				)
				(justify left bottom)
				(hide yes)
			)
		)
		(property "Author" "Antmicro"
			(at 108.585 94.615 0)
			(effects
				(font
					(size 1.27 1.27)
					(thickness 0.15)
				)
				(justify left bottom)
				(hide yes)
			)
		)
		(property "Voltage" ""
			(at 111.125 94.615 0)
			(effects
				(font
					(size 1.27 1.27)
				)
				(justify left bottom)
				(hide yes)
			)
		)
		(property "Dielectric" ""
			(at 113.665 94.615 0)
			(effects
				(font
					(size 1.27 1.27)
				)
				(justify left bottom)
				(hide yes)
			)
		)
		(pin "1"
		)
		(pin "2"
		)
		(instances
			(project "lpddr4-test-board"
				(path ""
					(reference "C20")
					(unit 1)
				)
			)
		)
	)
	(symbol
		(lib_id "antmicroCapacitorsmisc:C_100n_6V3_0402")
		(at 31.75 46.99 270)
		(unit 1)
		(exclude_from_sim no)
		(in_bom yes)
		(on_board yes)
		(dnp no)
		(property "Reference" "C9"
			(at 32.385 48.895 90)
			(effects
				(font
					(size 1.27 1.27)
					(thickness 0.15)
				)
				(justify left bottom)
			)
		)
		(property "Value" "C_100n_6V3_0402"
			(at 21.59 67.31 0)
			(effects
				(font
					(size 1.27 1.27)
					(thickness 0.15)
				)
				(justify left bottom)
				(hide yes)
			)
		)
		(property "Footprint" "antmicro-footprints:C_0402_1005Metric"
			(at 19.05 67.31 0)
			(effects
				(font
					(size 1.27 1.27)
					(thickness 0.15)
				)
				(justify left bottom)
				(hide yes)
			)
		)
		(property "Datasheet" " "
			(at 16.51 67.31 0)
			(effects
				(font
					(size 1.27 1.27)
					(thickness 0.15)
				)
				(justify left bottom)
				(hide yes)
			)
		)
		(property "Description" ""
			(at 31.75 46.99 0)
			(effects
				(font
					(size 1.27 1.27)
				)
			)
		)
		(property "Manufacturer" "Walsin"
			(at 11.43 67.31 0)
			(effects
				(font
					(size 1.27 1.27)
					(thickness 0.15)
				)
				(justify left bottom)
				(hide yes)
			)
		)
		(property "MPN" "0402X104K6R3CT"
			(at 13.97 67.31 0)
			(effects
				(font
					(size 1.27 1.27)
					(thickness 0.15)
				)
				(justify left bottom)
				(hide yes)
			)
		)
		(property "Val" "100n"
			(at 32.385 52.705 90)
			(effects
				(font
					(size 1.27 1.27)
					(thickness 0.15)
				)
				(justify left bottom)
			)
		)
		(property "License" "Apache-2.0"
			(at 8.89 67.31 0)
			(effects
				(font
					(size 1.27 1.27)
					(thickness 0.15)
				)
				(justify left bottom)
				(hide yes)
			)
		)
		(property "Author" "Antmicro"
			(at 6.35 67.31 0)
			(effects
				(font
					(size 1.27 1.27)
					(thickness 0.15)
				)
				(justify left bottom)
				(hide yes)
			)
		)
		(property "Voltage" ""
			(at 3.81 67.31 0)
			(effects
				(font
					(size 1.27 1.27)
				)
				(justify left bottom)
				(hide yes)
			)
		)
		(property "Dielectric" ""
			(at 1.27 67.31 0)
			(effects
				(font
					(size 1.27 1.27)
				)
				(justify left bottom)
				(hide yes)
			)
		)
		(pin "1"
		)
		(pin "2"
		)
		(instances
			(project "lpddr4-test-board"
				(path ""
					(reference "C9")
					(unit 1)
				)
			)
		)
	)
	(symbol
		(lib_id "antmicroCapacitorsmisc:C_100n_6V3_0402")
		(at 38.735 46.99 270)
		(unit 1)
		(exclude_from_sim no)
		(in_bom yes)
		(on_board yes)
		(dnp no)
		(property "Reference" "C12"
			(at 39.37 48.895 90)
			(effects
				(font
					(size 1.27 1.27)
					(thickness 0.15)
				)
				(justify left bottom)
			)
		)
		(property "Value" "C_100n_6V3_0402"
			(at 28.575 67.31 0)
			(effects
				(font
					(size 1.27 1.27)
					(thickness 0.15)
				)
				(justify left bottom)
				(hide yes)
			)
		)
		(property "Footprint" "antmicro-footprints:C_0402_1005Metric"
			(at 26.035 67.31 0)
			(effects
				(font
					(size 1.27 1.27)
					(thickness 0.15)
				)
				(justify left bottom)
				(hide yes)
			)
		)
		(property "Datasheet" " "
			(at 23.495 67.31 0)
			(effects
				(font
					(size 1.27 1.27)
					(thickness 0.15)
				)
				(justify left bottom)
				(hide yes)
			)
		)
		(property "Description" ""
			(at 38.735 46.99 0)
			(effects
				(font
					(size 1.27 1.27)
				)
			)
		)
		(property "Manufacturer" "Walsin"
			(at 18.415 67.31 0)
			(effects
				(font
					(size 1.27 1.27)
					(thickness 0.15)
				)
				(justify left bottom)
				(hide yes)
			)
		)
		(property "MPN" "0402X104K6R3CT"
			(at 20.955 67.31 0)
			(effects
				(font
					(size 1.27 1.27)
					(thickness 0.15)
				)
				(justify left bottom)
				(hide yes)
			)
		)
		(property "Val" "100n"
			(at 39.37 52.705 90)
			(effects
				(font
					(size 1.27 1.27)
					(thickness 0.15)
				)
				(justify left bottom)
			)
		)
		(property "License" "Apache-2.0"
			(at 15.875 67.31 0)
			(effects
				(font
					(size 1.27 1.27)
					(thickness 0.15)
				)
				(justify left bottom)
				(hide yes)
			)
		)
		(property "Author" "Antmicro"
			(at 13.335 67.31 0)
			(effects
				(font
					(size 1.27 1.27)
					(thickness 0.15)
				)
				(justify left bottom)
				(hide yes)
			)
		)
		(property "Voltage" ""
			(at 10.795 67.31 0)
			(effects
				(font
					(size 1.27 1.27)
				)
				(justify left bottom)
				(hide yes)
			)
		)
		(property "Dielectric" ""
			(at 8.255 67.31 0)
			(effects
				(font
					(size 1.27 1.27)
				)
				(justify left bottom)
				(hide yes)
			)
		)
		(pin "1"
		)
		(pin "2"
		)
		(instances
			(project "lpddr4-test-board"
				(path ""
					(reference "C12")
					(unit 1)
				)
			)
		)
	)
	(symbol
		(lib_id "antmicroCapacitorsmisc:C_100n_6V3_0402")
		(at 45.72 46.99 270)
		(unit 1)
		(exclude_from_sim no)
		(in_bom yes)
		(on_board yes)
		(dnp no)
		(property "Reference" "C15"
			(at 46.355 48.895 90)
			(effects
				(font
					(size 1.27 1.27)
					(thickness 0.15)
				)
				(justify left bottom)
			)
		)
		(property "Value" "C_100n_6V3_0402"
			(at 35.56 67.31 0)
			(effects
				(font
					(size 1.27 1.27)
					(thickness 0.15)
				)
				(justify left bottom)
				(hide yes)
			)
		)
		(property "Footprint" "antmicro-footprints:C_0402_1005Metric"
			(at 33.02 67.31 0)
			(effects
				(font
					(size 1.27 1.27)
					(thickness 0.15)
				)
				(justify left bottom)
				(hide yes)
			)
		)
		(property "Datasheet" " "
			(at 30.48 67.31 0)
			(effects
				(font
					(size 1.27 1.27)
					(thickness 0.15)
				)
				(justify left bottom)
				(hide yes)
			)
		)
		(property "Description" ""
			(at 45.72 46.99 0)
			(effects
				(font
					(size 1.27 1.27)
				)
			)
		)
		(property "Manufacturer" "Walsin"
			(at 25.4 67.31 0)
			(effects
				(font
					(size 1.27 1.27)
					(thickness 0.15)
				)
				(justify left bottom)
				(hide yes)
			)
		)
		(property "MPN" "0402X104K6R3CT"
			(at 27.94 67.31 0)
			(effects
				(font
					(size 1.27 1.27)
					(thickness 0.15)
				)
				(justify left bottom)
				(hide yes)
			)
		)
		(property "Val" "100n"
			(at 46.355 52.705 90)
			(effects
				(font
					(size 1.27 1.27)
					(thickness 0.15)
				)
				(justify left bottom)
			)
		)
		(property "License" "Apache-2.0"
			(at 22.86 67.31 0)
			(effects
				(font
					(size 1.27 1.27)
					(thickness 0.15)
				)
				(justify left bottom)
				(hide yes)
			)
		)
		(property "Author" "Antmicro"
			(at 20.32 67.31 0)
			(effects
				(font
					(size 1.27 1.27)
					(thickness 0.15)
				)
				(justify left bottom)
				(hide yes)
			)
		)
		(property "Voltage" ""
			(at 17.78 67.31 0)
			(effects
				(font
					(size 1.27 1.27)
				)
				(justify left bottom)
				(hide yes)
			)
		)
		(property "Dielectric" ""
			(at 15.24 67.31 0)
			(effects
				(font
					(size 1.27 1.27)
				)
				(justify left bottom)
				(hide yes)
			)
		)
		(pin "1"
		)
		(pin "2"
		)
		(instances
			(project "lpddr4-test-board"
				(path ""
					(reference "C15")
					(unit 1)
				)
			)
		)
	)
	(symbol
		(lib_id "antmicroCapacitorsmisc:C_100n_6V3_0402")
		(at 52.705 46.99 270)
		(unit 1)
		(exclude_from_sim no)
		(in_bom yes)
		(on_board yes)
		(dnp no)
		(property "Reference" "C19"
			(at 53.34 48.895 90)
			(effects
				(font
					(size 1.27 1.27)
					(thickness 0.15)
				)
				(justify left bottom)
			)
		)
		(property "Value" "C_100n_6V3_0402"
			(at 42.545 67.31 0)
			(effects
				(font
					(size 1.27 1.27)
					(thickness 0.15)
				)
				(justify left bottom)
				(hide yes)
			)
		)
		(property "Footprint" "antmicro-footprints:C_0402_1005Metric"
			(at 40.005 67.31 0)
			(effects
				(font
					(size 1.27 1.27)
					(thickness 0.15)
				)
				(justify left bottom)
				(hide yes)
			)
		)
		(property "Datasheet" " "
			(at 37.465 67.31 0)
			(effects
				(font
					(size 1.27 1.27)
					(thickness 0.15)
				)
				(justify left bottom)
				(hide yes)
			)
		)
		(property "Description" ""
			(at 52.705 46.99 0)
			(effects
				(font
					(size 1.27 1.27)
				)
			)
		)
		(property "Manufacturer" "Walsin"
			(at 32.385 67.31 0)
			(effects
				(font
					(size 1.27 1.27)
					(thickness 0.15)
				)
				(justify left bottom)
				(hide yes)
			)
		)
		(property "MPN" "0402X104K6R3CT"
			(at 34.925 67.31 0)
			(effects
				(font
					(size 1.27 1.27)
					(thickness 0.15)
				)
				(justify left bottom)
				(hide yes)
			)
		)
		(property "Val" "100n"
			(at 53.34 52.705 90)
			(effects
				(font
					(size 1.27 1.27)
					(thickness 0.15)
				)
				(justify left bottom)
			)
		)
		(property "License" "Apache-2.0"
			(at 29.845 67.31 0)
			(effects
				(font
					(size 1.27 1.27)
					(thickness 0.15)
				)
				(justify left bottom)
				(hide yes)
			)
		)
		(property "Author" "Antmicro"
			(at 27.305 67.31 0)
			(effects
				(font
					(size 1.27 1.27)
					(thickness 0.15)
				)
				(justify left bottom)
				(hide yes)
			)
		)
		(property "Voltage" ""
			(at 24.765 67.31 0)
			(effects
				(font
					(size 1.27 1.27)
				)
				(justify left bottom)
				(hide yes)
			)
		)
		(property "Dielectric" ""
			(at 22.225 67.31 0)
			(effects
				(font
					(size 1.27 1.27)
				)
				(justify left bottom)
				(hide yes)
			)
		)
		(pin "1"
		)
		(pin "2"
		)
		(instances
			(project "lpddr4-test-board"
				(path ""
					(reference "C19")
					(unit 1)
				)
			)
		)
	)
	(symbol
		(lib_id "antmicropower:GND")
		(at 31.75 53.34 0)
		(unit 1)
		(exclude_from_sim no)
		(in_bom yes)
		(on_board yes)
		(dnp no)
		(property "Reference" "#PWR013"
			(at 40.64 55.88 0)
			(effects
				(font
					(size 1.27 1.27)
					(thickness 0.15)
				)
				(justify left bottom)
				(hide yes)
			)
		)
		(property "Value" "GND"
			(at 29.845 57.785 0)
			(effects
				(font
					(size 1.27 1.27)
					(thickness 0.15)
				)
				(justify left bottom)
			)
		)
		(property "Footprint" ""
			(at 40.64 60.96 0)
			(effects
				(font
					(size 1.27 1.27)
					(thickness 0.15)
				)
				(justify left bottom)
				(hide yes)
			)
		)
		(property "Datasheet" ""
			(at 40.64 66.04 0)
			(effects
				(font
					(size 1.27 1.27)
					(thickness 0.15)
				)
				(justify left bottom)
				(hide yes)
			)
		)
		(property "Description" ""
			(at 31.75 53.34 0)
			(effects
				(font
					(size 1.27 1.27)
				)
			)
		)
		(property "Author" "Antmicro"
			(at 40.64 60.96 0)
			(effects
				(font
					(size 1.27 1.27)
					(thickness 0.15)
				)
				(justify left bottom)
				(hide yes)
			)
		)
		(property "License" "Apache-2.0"
			(at 40.64 63.5 0)
			(effects
				(font
					(size 1.27 1.27)
					(thickness 0.15)
				)
				(justify left bottom)
				(hide yes)
			)
		)
		(pin "1"
		)
		(instances
			(project "lpddr4-test-board"
				(path ""
					(reference "#PWR013")
					(unit 1)
				)
			)
		)
	)
	(symbol
		(lib_id "antmicropower:GND")
		(at 38.735 53.34 0)
		(unit 1)
		(exclude_from_sim no)
		(in_bom yes)
		(on_board yes)
		(dnp no)
		(property "Reference" "#PWR015"
			(at 47.625 55.88 0)
			(effects
				(font
					(size 1.27 1.27)
					(thickness 0.15)
				)
				(justify left bottom)
				(hide yes)
			)
		)
		(property "Value" "GND"
			(at 36.83 57.785 0)
			(effects
				(font
					(size 1.27 1.27)
					(thickness 0.15)
				)
				(justify left bottom)
			)
		)
		(property "Footprint" ""
			(at 47.625 60.96 0)
			(effects
				(font
					(size 1.27 1.27)
					(thickness 0.15)
				)
				(justify left bottom)
				(hide yes)
			)
		)
		(property "Datasheet" ""
			(at 47.625 66.04 0)
			(effects
				(font
					(size 1.27 1.27)
					(thickness 0.15)
				)
				(justify left bottom)
				(hide yes)
			)
		)
		(property "Description" ""
			(at 38.735 53.34 0)
			(effects
				(font
					(size 1.27 1.27)
				)
			)
		)
		(property "Author" "Antmicro"
			(at 47.625 60.96 0)
			(effects
				(font
					(size 1.27 1.27)
					(thickness 0.15)
				)
				(justify left bottom)
				(hide yes)
			)
		)
		(property "License" "Apache-2.0"
			(at 47.625 63.5 0)
			(effects
				(font
					(size 1.27 1.27)
					(thickness 0.15)
				)
				(justify left bottom)
				(hide yes)
			)
		)
		(pin "1"
		)
		(instances
			(project "lpddr4-test-board"
				(path ""
					(reference "#PWR015")
					(unit 1)
				)
			)
		)
	)
	(symbol
		(lib_id "antmicropower:GND")
		(at 45.72 53.34 0)
		(unit 1)
		(exclude_from_sim no)
		(in_bom yes)
		(on_board yes)
		(dnp no)
		(property "Reference" "#PWR017"
			(at 54.61 55.88 0)
			(effects
				(font
					(size 1.27 1.27)
					(thickness 0.15)
				)
				(justify left bottom)
				(hide yes)
			)
		)
		(property "Value" "GND"
			(at 43.815 57.785 0)
			(effects
				(font
					(size 1.27 1.27)
					(thickness 0.15)
				)
				(justify left bottom)
			)
		)
		(property "Footprint" ""
			(at 54.61 60.96 0)
			(effects
				(font
					(size 1.27 1.27)
					(thickness 0.15)
				)
				(justify left bottom)
				(hide yes)
			)
		)
		(property "Datasheet" ""
			(at 54.61 66.04 0)
			(effects
				(font
					(size 1.27 1.27)
					(thickness 0.15)
				)
				(justify left bottom)
				(hide yes)
			)
		)
		(property "Description" ""
			(at 45.72 53.34 0)
			(effects
				(font
					(size 1.27 1.27)
				)
			)
		)
		(property "Author" "Antmicro"
			(at 54.61 60.96 0)
			(effects
				(font
					(size 1.27 1.27)
					(thickness 0.15)
				)
				(justify left bottom)
				(hide yes)
			)
		)
		(property "License" "Apache-2.0"
			(at 54.61 63.5 0)
			(effects
				(font
					(size 1.27 1.27)
					(thickness 0.15)
				)
				(justify left bottom)
				(hide yes)
			)
		)
		(pin "1"
		)
		(instances
			(project "lpddr4-test-board"
				(path ""
					(reference "#PWR017")
					(unit 1)
				)
			)
		)
	)
	(symbol
		(lib_id "antmicropower:GND")
		(at 52.705 53.34 0)
		(unit 1)
		(exclude_from_sim no)
		(in_bom yes)
		(on_board yes)
		(dnp no)
		(property "Reference" "#PWR020"
			(at 61.595 55.88 0)
			(effects
				(font
					(size 1.27 1.27)
					(thickness 0.15)
				)
				(justify left bottom)
				(hide yes)
			)
		)
		(property "Value" "GND"
			(at 50.8 57.785 0)
			(effects
				(font
					(size 1.27 1.27)
					(thickness 0.15)
				)
				(justify left bottom)
			)
		)
		(property "Footprint" ""
			(at 61.595 60.96 0)
			(effects
				(font
					(size 1.27 1.27)
					(thickness 0.15)
				)
				(justify left bottom)
				(hide yes)
			)
		)
		(property "Datasheet" ""
			(at 61.595 66.04 0)
			(effects
				(font
					(size 1.27 1.27)
					(thickness 0.15)
				)
				(justify left bottom)
				(hide yes)
			)
		)
		(property "Description" ""
			(at 52.705 53.34 0)
			(effects
				(font
					(size 1.27 1.27)
				)
			)
		)
		(property "Author" "Antmicro"
			(at 61.595 60.96 0)
			(effects
				(font
					(size 1.27 1.27)
					(thickness 0.15)
				)
				(justify left bottom)
				(hide yes)
			)
		)
		(property "License" "Apache-2.0"
			(at 61.595 63.5 0)
			(effects
				(font
					(size 1.27 1.27)
					(thickness 0.15)
				)
				(justify left bottom)
				(hide yes)
			)
		)
		(pin "1"
		)
		(instances
			(project "lpddr4-test-board"
				(path ""
					(reference "#PWR020")
					(unit 1)
				)
			)
		)
	)
	(symbol
		(lib_id "antmicroCapacitorsmisc:C_100n_6V3_0402")
		(at 38.735 70.485 90)
		(unit 1)
		(exclude_from_sim no)
		(in_bom yes)
		(on_board yes)
		(dnp no)
		(property "Reference" "C13"
			(at 39.37 67.31 90)
			(effects
				(font
					(size 1.27 1.27)
					(thickness 0.15)
				)
				(justify right top)
			)
		)
		(property "Value" "C_100n_6V3_0402"
			(at 48.895 50.165 0)
			(effects
				(font
					(size 1.27 1.27)
					(thickness 0.15)
				)
				(justify left bottom)
				(hide yes)
			)
		)
		(property "Footprint" "antmicro-footprints:C_0402_1005Metric"
			(at 51.435 50.165 0)
			(effects
				(font
					(size 1.27 1.27)
					(thickness 0.15)
				)
				(justify left bottom)
				(hide yes)
			)
		)
		(property "Datasheet" " "
			(at 53.975 50.165 0)
			(effects
				(font
					(size 1.27 1.27)
					(thickness 0.15)
				)
				(justify left bottom)
				(hide yes)
			)
		)
		(property "Description" ""
			(at 38.735 70.485 0)
			(effects
				(font
					(size 1.27 1.27)
				)
			)
		)
		(property "Manufacturer" "Walsin"
			(at 59.055 50.165 0)
			(effects
				(font
					(size 1.27 1.27)
					(thickness 0.15)
				)
				(justify left bottom)
				(hide yes)
			)
		)
		(property "MPN" "0402X104K6R3CT"
			(at 56.515 50.165 0)
			(effects
				(font
					(size 1.27 1.27)
					(thickness 0.15)
				)
				(justify left bottom)
				(hide yes)
			)
		)
		(property "Val" "100n"
			(at 39.37 71.12 90)
			(effects
				(font
					(size 1.27 1.27)
					(thickness 0.15)
				)
				(justify right top)
			)
		)
		(property "License" "Apache-2.0"
			(at 61.595 50.165 0)
			(effects
				(font
					(size 1.27 1.27)
					(thickness 0.15)
				)
				(justify left bottom)
				(hide yes)
			)
		)
		(property "Author" "Antmicro"
			(at 64.135 50.165 0)
			(effects
				(font
					(size 1.27 1.27)
					(thickness 0.15)
				)
				(justify left bottom)
				(hide yes)
			)
		)
		(property "Voltage" ""
			(at 66.675 50.165 0)
			(effects
				(font
					(size 1.27 1.27)
				)
				(justify left bottom)
				(hide yes)
			)
		)
		(property "Dielectric" ""
			(at 69.215 50.165 0)
			(effects
				(font
					(size 1.27 1.27)
				)
				(justify left bottom)
				(hide yes)
			)
		)
		(pin "1"
		)
		(pin "2"
		)
		(instances
			(project "lpddr4-test-board"
				(path ""
					(reference "C13")
					(unit 1)
				)
			)
		)
	)
	(symbol
		(lib_id "antmicroCapacitorsmisc:C_100n_6V3_0402")
		(at 45.72 70.485 90)
		(unit 1)
		(exclude_from_sim no)
		(in_bom yes)
		(on_board yes)
		(dnp no)
		(property "Reference" "C17"
			(at 46.355 67.31 90)
			(effects
				(font
					(size 1.27 1.27)
					(thickness 0.15)
				)
				(justify right top)
			)
		)
		(property "Value" "C_100n_6V3_0402"
			(at 55.88 50.165 0)
			(effects
				(font
					(size 1.27 1.27)
					(thickness 0.15)
				)
				(justify left bottom)
				(hide yes)
			)
		)
		(property "Footprint" "antmicro-footprints:C_0402_1005Metric"
			(at 58.42 50.165 0)
			(effects
				(font
					(size 1.27 1.27)
					(thickness 0.15)
				)
				(justify left bottom)
				(hide yes)
			)
		)
		(property "Datasheet" " "
			(at 60.96 50.165 0)
			(effects
				(font
					(size 1.27 1.27)
					(thickness 0.15)
				)
				(justify left bottom)
				(hide yes)
			)
		)
		(property "Description" ""
			(at 45.72 70.485 0)
			(effects
				(font
					(size 1.27 1.27)
				)
			)
		)
		(property "Manufacturer" "Walsin"
			(at 66.04 50.165 0)
			(effects
				(font
					(size 1.27 1.27)
					(thickness 0.15)
				)
				(justify left bottom)
				(hide yes)
			)
		)
		(property "MPN" "0402X104K6R3CT"
			(at 63.5 50.165 0)
			(effects
				(font
					(size 1.27 1.27)
					(thickness 0.15)
				)
				(justify left bottom)
				(hide yes)
			)
		)
		(property "Val" "100n"
			(at 46.355 71.12 90)
			(effects
				(font
					(size 1.27 1.27)
					(thickness 0.15)
				)
				(justify right top)
			)
		)
		(property "License" "Apache-2.0"
			(at 68.58 50.165 0)
			(effects
				(font
					(size 1.27 1.27)
					(thickness 0.15)
				)
				(justify left bottom)
				(hide yes)
			)
		)
		(property "Author" "Antmicro"
			(at 71.12 50.165 0)
			(effects
				(font
					(size 1.27 1.27)
					(thickness 0.15)
				)
				(justify left bottom)
				(hide yes)
			)
		)
		(property "Voltage" ""
			(at 73.66 50.165 0)
			(effects
				(font
					(size 1.27 1.27)
				)
				(justify left bottom)
				(hide yes)
			)
		)
		(property "Dielectric" ""
			(at 76.2 50.165 0)
			(effects
				(font
					(size 1.27 1.27)
				)
				(justify left bottom)
				(hide yes)
			)
		)
		(pin "1"
		)
		(pin "2"
		)
		(instances
			(project "lpddr4-test-board"
				(path ""
					(reference "C17")
					(unit 1)
				)
			)
		)
	)
	(symbol
		(lib_id "antmicropower:GND")
		(at 38.735 71.755 0)
		(unit 1)
		(exclude_from_sim no)
		(in_bom yes)
		(on_board yes)
		(dnp no)
		(property "Reference" "#PWR016"
			(at 47.625 74.295 0)
			(effects
				(font
					(size 1.27 1.27)
					(thickness 0.15)
				)
				(justify left bottom)
				(hide yes)
			)
		)
		(property "Value" "GND"
			(at 36.83 76.2 0)
			(effects
				(font
					(size 1.27 1.27)
					(thickness 0.15)
				)
				(justify left bottom)
			)
		)
		(property "Footprint" ""
			(at 47.625 79.375 0)
			(effects
				(font
					(size 1.27 1.27)
					(thickness 0.15)
				)
				(justify left bottom)
				(hide yes)
			)
		)
		(property "Datasheet" ""
			(at 47.625 84.455 0)
			(effects
				(font
					(size 1.27 1.27)
					(thickness 0.15)
				)
				(justify left bottom)
				(hide yes)
			)
		)
		(property "Description" ""
			(at 38.735 71.755 0)
			(effects
				(font
					(size 1.27 1.27)
				)
			)
		)
		(property "Author" "Antmicro"
			(at 47.625 79.375 0)
			(effects
				(font
					(size 1.27 1.27)
					(thickness 0.15)
				)
				(justify left bottom)
				(hide yes)
			)
		)
		(property "License" "Apache-2.0"
			(at 47.625 81.915 0)
			(effects
				(font
					(size 1.27 1.27)
					(thickness 0.15)
				)
				(justify left bottom)
				(hide yes)
			)
		)
		(pin "1"
		)
		(instances
			(project "lpddr4-test-board"
				(path ""
					(reference "#PWR016")
					(unit 1)
				)
			)
		)
	)
	(symbol
		(lib_id "antmicropower:GND")
		(at 45.72 71.755 0)
		(unit 1)
		(exclude_from_sim no)
		(in_bom yes)
		(on_board yes)
		(dnp no)
		(property "Reference" "#PWR019"
			(at 54.61 74.295 0)
			(effects
				(font
					(size 1.27 1.27)
					(thickness 0.15)
				)
				(justify left bottom)
				(hide yes)
			)
		)
		(property "Value" "GND"
			(at 43.815 76.2 0)
			(effects
				(font
					(size 1.27 1.27)
					(thickness 0.15)
				)
				(justify left bottom)
			)
		)
		(property "Footprint" ""
			(at 54.61 79.375 0)
			(effects
				(font
					(size 1.27 1.27)
					(thickness 0.15)
				)
				(justify left bottom)
				(hide yes)
			)
		)
		(property "Datasheet" ""
			(at 54.61 84.455 0)
			(effects
				(font
					(size 1.27 1.27)
					(thickness 0.15)
				)
				(justify left bottom)
				(hide yes)
			)
		)
		(property "Description" ""
			(at 45.72 71.755 0)
			(effects
				(font
					(size 1.27 1.27)
				)
			)
		)
		(property "Author" "Antmicro"
			(at 54.61 79.375 0)
			(effects
				(font
					(size 1.27 1.27)
					(thickness 0.15)
				)
				(justify left bottom)
				(hide yes)
			)
		)
		(property "License" "Apache-2.0"
			(at 54.61 81.915 0)
			(effects
				(font
					(size 1.27 1.27)
					(thickness 0.15)
				)
				(justify left bottom)
				(hide yes)
			)
		)
		(pin "1"
		)
		(instances
			(project "lpddr4-test-board"
				(path ""
					(reference "#PWR019")
					(unit 1)
				)
			)
		)
	)
	(symbol
		(lib_id "antmicroCapacitors0402:C_4u7_0402")
		(at 31.75 70.485 90)
		(unit 1)
		(exclude_from_sim no)
		(in_bom yes)
		(on_board yes)
		(dnp no)
		(property "Reference" "C10"
			(at 32.385 67.31 90)
			(effects
				(font
					(size 1.27 1.27)
					(thickness 0.15)
				)
				(justify right top)
			)
		)
		(property "Value" "C_4u7_0402"
			(at 41.91 50.165 0)
			(effects
				(font
					(size 1.27 1.27)
					(thickness 0.15)
				)
				(justify left bottom)
				(hide yes)
			)
		)
		(property "Footprint" "antmicro-footprints:C_0402_1005Metric"
			(at 44.45 50.165 0)
			(effects
				(font
					(size 1.27 1.27)
					(thickness 0.15)
				)
				(justify left bottom)
				(hide yes)
			)
		)
		(property "Datasheet" " "
			(at 46.99 50.165 0)
			(effects
				(font
					(size 1.27 1.27)
					(thickness 0.15)
				)
				(justify left bottom)
				(hide yes)
			)
		)
		(property "Description" ""
			(at 31.75 70.485 0)
			(effects
				(font
					(size 1.27 1.27)
				)
			)
		)
		(property "Manufacturer" "Murata"
			(at 52.07 50.165 0)
			(effects
				(font
					(size 1.27 1.27)
					(thickness 0.15)
				)
				(justify left bottom)
				(hide yes)
			)
		)
		(property "MPN" "GRM155R61A475MEAAD"
			(at 49.53 50.165 0)
			(effects
				(font
					(size 1.27 1.27)
					(thickness 0.15)
				)
				(justify left bottom)
				(hide yes)
			)
		)
		(property "Val" "4u7"
			(at 32.385 71.12 90)
			(effects
				(font
					(size 1.27 1.27)
					(thickness 0.15)
				)
				(justify right top)
			)
		)
		(property "License" "Apache-2.0"
			(at 54.61 50.165 0)
			(effects
				(font
					(size 1.27 1.27)
					(thickness 0.15)
				)
				(justify left bottom)
				(hide yes)
			)
		)
		(property "Author" "Antmicro"
			(at 57.15 50.165 0)
			(effects
				(font
					(size 1.27 1.27)
					(thickness 0.15)
				)
				(justify left bottom)
				(hide yes)
			)
		)
		(property "Voltage" ""
			(at 59.69 50.165 0)
			(effects
				(font
					(size 1.27 1.27)
				)
				(justify left bottom)
				(hide yes)
			)
		)
		(property "Dielectric" ""
			(at 62.23 50.165 0)
			(effects
				(font
					(size 1.27 1.27)
				)
				(justify left bottom)
				(hide yes)
			)
		)
		(pin "1"
		)
		(pin "2"
		)
		(instances
			(project "lpddr4-test-board"
				(path ""
					(reference "C10")
					(unit 1)
				)
			)
		)
	)
	(symbol
		(lib_id "antmicropower:GND")
		(at 31.75 71.755 0)
		(unit 1)
		(exclude_from_sim no)
		(in_bom yes)
		(on_board yes)
		(dnp no)
		(property "Reference" "#PWR014"
			(at 40.64 74.295 0)
			(effects
				(font
					(size 1.27 1.27)
					(thickness 0.15)
				)
				(justify left bottom)
				(hide yes)
			)
		)
		(property "Value" "GND"
			(at 29.845 76.2 0)
			(effects
				(font
					(size 1.27 1.27)
					(thickness 0.15)
				)
				(justify left bottom)
			)
		)
		(property "Footprint" ""
			(at 40.64 79.375 0)
			(effects
				(font
					(size 1.27 1.27)
					(thickness 0.15)
				)
				(justify left bottom)
				(hide yes)
			)
		)
		(property "Datasheet" ""
			(at 40.64 84.455 0)
			(effects
				(font
					(size 1.27 1.27)
					(thickness 0.15)
				)
				(justify left bottom)
				(hide yes)
			)
		)
		(property "Description" ""
			(at 31.75 71.755 0)
			(effects
				(font
					(size 1.27 1.27)
				)
			)
		)
		(property "Author" "Antmicro"
			(at 40.64 79.375 0)
			(effects
				(font
					(size 1.27 1.27)
					(thickness 0.15)
				)
				(justify left bottom)
				(hide yes)
			)
		)
		(property "License" "Apache-2.0"
			(at 40.64 81.915 0)
			(effects
				(font
					(size 1.27 1.27)
					(thickness 0.15)
				)
				(justify left bottom)
				(hide yes)
			)
		)
		(pin "1"
		)
		(instances
			(project "lpddr4-test-board"
				(path ""
					(reference "#PWR014")
					(unit 1)
				)
			)
		)
	)
	(symbol
		(lib_id "antmicroResistors0402:R_330R_0402")
		(at 171.45 240.665 0)
		(unit 1)
		(exclude_from_sim no)
		(in_bom yes)
		(on_board yes)
		(dnp no)
		(property "Reference" "R28"
			(at 176.53 240.665 0)
			(effects
				(font
					(size 1.27 1.27)
					(thickness 0.15)
				)
				(justify left bottom)
			)
		)
		(property "Value" "R_330R_0402"
			(at 191.77 253.365 0)
			(effects
				(font
					(size 1.27 1.27)
					(thickness 0.15)
				)
				(justify left bottom)
				(hide yes)
			)
		)
		(property "Footprint" "antmicro-footprints:R_0402_1005Metric"
			(at 191.77 255.905 0)
			(effects
				(font
					(size 1.27 1.27)
					(thickness 0.15)
				)
				(justify left bottom)
				(hide yes)
			)
		)
		(property "Datasheet" "https://www.bourns.com/docs/product-datasheets/cr.pdf"
			(at 191.77 258.445 0)
			(effects
				(font
					(size 1.27 1.27)
					(thickness 0.15)
				)
				(justify left bottom)
				(hide yes)
			)
		)
		(property "Description" ""
			(at 171.45 240.665 0)
			(effects
				(font
					(size 1.27 1.27)
				)
			)
		)
		(property "Manufacturer" "Bourns"
			(at 191.77 263.525 0)
			(effects
				(font
					(size 1.27 1.27)
					(thickness 0.15)
				)
				(justify left bottom)
				(hide yes)
			)
		)
		(property "MPN" "CR0402-FX-3300GLF"
			(at 191.77 260.985 0)
			(effects
				(font
					(size 1.27 1.27)
					(thickness 0.15)
				)
				(justify left bottom)
				(hide yes)
			)
		)
		(property "Val" "330R"
			(at 166.37 240.665 0)
			(effects
				(font
					(size 1.27 1.27)
					(thickness 0.15)
				)
				(justify left bottom)
			)
		)
		(property "License" "Apache-2.0"
			(at 191.77 266.065 0)
			(effects
				(font
					(size 1.27 1.27)
					(thickness 0.15)
				)
				(justify left bottom)
				(hide yes)
			)
		)
		(property "Author" "Antmicro"
			(at 191.77 268.605 0)
			(effects
				(font
					(size 1.27 1.27)
					(thickness 0.15)
				)
				(justify left bottom)
				(hide yes)
			)
		)
		(property "Tolerance" "1%"
			(at 191.77 250.825 0)
			(effects
				(font
					(size 1.27 1.27)
				)
				(justify left bottom)
				(hide yes)
			)
		)
		(pin "1"
		)
		(pin "2"
		)
		(instances
			(project "lpddr4-test-board"
				(path ""
					(reference "R28")
					(unit 1)
				)
			)
		)
	)
	(symbol
		(lib_id "antmicroLEDIndicationDiscrete:LED_G_0603_KP-1608CGCK")
		(at 156.845 240.665 0)
		(unit 1)
		(exclude_from_sim no)
		(in_bom yes)
		(on_board yes)
		(dnp no)
		(property "Reference" "D3"
			(at 159.385 235.585 0)
			(effects
				(font
					(size 1.27 1.27)
					(thickness 0.15)
				)
				(justify left bottom)
			)
		)
		(property "Value" "LED_G_0603_KP-1608CGCK"
			(at 146.685 238.125 0)
			(effects
				(font
					(size 1.27 1.27)
					(thickness 0.15)
				)
				(justify left bottom)
			)
		)
		(property "Footprint" "antmicro-footprints:LED_0603_1608Metric_G"
			(at 179.705 250.825 0)
			(effects
				(font
					(size 1.27 1.27)
					(thickness 0.15)
				)
				(justify left bottom)
				(hide yes)
			)
		)
		(property "Datasheet" "http://www.farnell.com/datasheets/2045956.pdf"
			(at 179.705 253.365 0)
			(effects
				(font
					(size 1.27 1.27)
					(thickness 0.15)
				)
				(justify left bottom)
				(hide yes)
			)
		)
		(property "Description" ""
			(at 156.845 240.665 0)
			(effects
				(font
					(size 1.27 1.27)
				)
			)
		)
		(property "MPN" "KP-1608CGCK"
			(at 179.705 255.905 0)
			(effects
				(font
					(size 1.27 1.27)
					(thickness 0.15)
				)
				(justify left bottom)
				(hide yes)
			)
		)
		(property "Manufacturer" "Kingbright"
			(at 179.705 258.445 0)
			(effects
				(font
					(size 1.27 1.27)
					(thickness 0.15)
				)
				(justify left bottom)
				(hide yes)
			)
		)
		(property "Author" "Antmicro"
			(at 179.705 260.985 0)
			(effects
				(font
					(size 1.27 1.27)
					(thickness 0.15)
				)
				(justify left bottom)
				(hide yes)
			)
		)
		(property "License" "Apache-2.0"
			(at 179.705 263.525 0)
			(effects
				(font
					(size 1.27 1.27)
					(thickness 0.15)
				)
				(justify left bottom)
				(hide yes)
			)
		)
		(pin "1"
		)
		(pin "2"
		)
		(instances
			(project "lpddr4-test-board"
				(path ""
					(reference "D3")
					(unit 1)
				)
			)
		)
	)
	(symbol
		(lib_id "antmicroFerriteBeadsandChips:FB_600Z_0.5A_Murata-BLM18AG_0603")
		(at 209.55 153.67 90)
		(unit 1)
		(exclude_from_sim no)
		(in_bom yes)
		(on_board yes)
		(dnp no)
		(property "Reference" "FB3"
			(at 212.09 151.13 90)
			(effects
				(font
					(size 1.27 1.27)
					(thickness 0.15)
				)
				(justify right top)
			)
		)
		(property "Value" "FB_600Z_0.5A_0603"
			(at 214.63 138.43 0)
			(effects
				(font
					(size 1.27 1.27)
					(thickness 0.15)
				)
				(justify left bottom)
				(hide yes)
			)
		)
		(property "Footprint" "antmicro-footprints:FB_0603_1608Metric"
			(at 217.17 138.43 0)
			(effects
				(font
					(size 1.27 1.27)
					(thickness 0.15)
				)
				(justify left bottom)
				(hide yes)
			)
		)
		(property "Datasheet" "https://www.murata.com/en-us/products/productdata/8796738650142/ENFA0003.pdf"
			(at 219.71 138.43 0)
			(effects
				(font
					(size 1.27 1.27)
					(thickness 0.15)
				)
				(justify left bottom)
				(hide yes)
			)
		)
		(property "Description" ""
			(at 209.55 153.67 0)
			(effects
				(font
					(size 1.27 1.27)
				)
			)
		)
		(property "MPN" "BLM18AG601SN1D"
			(at 212.09 153.67 90)
			(effects
				(font
					(size 1.27 1.27)
					(thickness 0.15)
				)
				(justify right top)
			)
		)
		(property "Manufacturer" "Murata"
			(at 224.79 138.43 0)
			(effects
				(font
					(size 1.27 1.27)
					(thickness 0.15)
				)
				(justify left bottom)
				(hide yes)
			)
		)
		(property "Author" "Antmicro"
			(at 227.33 138.43 0)
			(effects
				(font
					(size 1.27 1.27)
					(thickness 0.15)
				)
				(justify left bottom)
				(hide yes)
			)
		)
		(property "License" "Apache-2.0"
			(at 229.87 138.43 0)
			(effects
				(font
					(size 1.27 1.27)
					(thickness 0.15)
				)
				(justify left bottom)
				(hide yes)
			)
		)
		(pin "1"
		)
		(pin "2"
		)
		(instances
			(project "lpddr4-test-board"
				(path ""
					(reference "FB3")
					(unit 1)
				)
			)
		)
	)
	(symbol
		(lib_id "antmicroResistors0402:R_330R_0402")
		(at 234.315 220.98 0)
		(unit 1)
		(exclude_from_sim no)
		(in_bom yes)
		(on_board yes)
		(dnp no)
		(property "Reference" "R29"
			(at 239.395 220.98 0)
			(effects
				(font
					(size 1.27 1.27)
					(thickness 0.15)
				)
				(justify left bottom)
			)
		)
		(property "Value" "R_330R_0402"
			(at 254.635 233.68 0)
			(effects
				(font
					(size 1.27 1.27)
					(thickness 0.15)
				)
				(justify left bottom)
				(hide yes)
			)
		)
		(property "Footprint" "antmicro-footprints:R_0402_1005Metric"
			(at 254.635 236.22 0)
			(effects
				(font
					(size 1.27 1.27)
					(thickness 0.15)
				)
				(justify left bottom)
				(hide yes)
			)
		)
		(property "Datasheet" "https://www.bourns.com/docs/product-datasheets/cr.pdf"
			(at 254.635 238.76 0)
			(effects
				(font
					(size 1.27 1.27)
					(thickness 0.15)
				)
				(justify left bottom)
				(hide yes)
			)
		)
		(property "Description" ""
			(at 234.315 220.98 0)
			(effects
				(font
					(size 1.27 1.27)
				)
			)
		)
		(property "Manufacturer" "Bourns"
			(at 254.635 243.84 0)
			(effects
				(font
					(size 1.27 1.27)
					(thickness 0.15)
				)
				(justify left bottom)
				(hide yes)
			)
		)
		(property "MPN" "CR0402-FX-3300GLF"
			(at 254.635 241.3 0)
			(effects
				(font
					(size 1.27 1.27)
					(thickness 0.15)
				)
				(justify left bottom)
				(hide yes)
			)
		)
		(property "Val" "330R"
			(at 229.235 220.98 0)
			(effects
				(font
					(size 1.27 1.27)
					(thickness 0.15)
				)
				(justify left bottom)
			)
		)
		(property "License" "Apache-2.0"
			(at 254.635 246.38 0)
			(effects
				(font
					(size 1.27 1.27)
					(thickness 0.15)
				)
				(justify left bottom)
				(hide yes)
			)
		)
		(property "Author" "Antmicro"
			(at 254.635 248.92 0)
			(effects
				(font
					(size 1.27 1.27)
					(thickness 0.15)
				)
				(justify left bottom)
				(hide yes)
			)
		)
		(property "Tolerance" "1%"
			(at 254.635 231.14 0)
			(effects
				(font
					(size 1.27 1.27)
				)
				(justify left bottom)
				(hide yes)
			)
		)
		(pin "1"
		)
		(pin "2"
		)
		(instances
			(project "lpddr4-test-board"
				(path ""
					(reference "R29")
					(unit 1)
				)
			)
		)
	)
	(symbol
		(lib_id "antmicroLEDIndicationDiscrete:LED_G_0603_KP-1608CGCK")
		(at 219.71 220.98 0)
		(unit 1)
		(exclude_from_sim no)
		(in_bom yes)
		(on_board yes)
		(dnp no)
		(property "Reference" "D5"
			(at 222.25 215.9 0)
			(effects
				(font
					(size 1.27 1.27)
					(thickness 0.15)
				)
				(justify left bottom)
			)
		)
		(property "Value" "LED_G_0603_KP-1608CGCK"
			(at 209.55 218.44 0)
			(effects
				(font
					(size 1.27 1.27)
					(thickness 0.15)
				)
				(justify left bottom)
			)
		)
		(property "Footprint" "antmicro-footprints:LED_0603_1608Metric_G"
			(at 242.57 231.14 0)
			(effects
				(font
					(size 1.27 1.27)
					(thickness 0.15)
				)
				(justify left bottom)
				(hide yes)
			)
		)
		(property "Datasheet" "http://www.farnell.com/datasheets/2045956.pdf"
			(at 242.57 233.68 0)
			(effects
				(font
					(size 1.27 1.27)
					(thickness 0.15)
				)
				(justify left bottom)
				(hide yes)
			)
		)
		(property "Description" ""
			(at 219.71 220.98 0)
			(effects
				(font
					(size 1.27 1.27)
				)
			)
		)
		(property "MPN" "KP-1608CGCK"
			(at 242.57 236.22 0)
			(effects
				(font
					(size 1.27 1.27)
					(thickness 0.15)
				)
				(justify left bottom)
				(hide yes)
			)
		)
		(property "Manufacturer" "Kingbright"
			(at 242.57 238.76 0)
			(effects
				(font
					(size 1.27 1.27)
					(thickness 0.15)
				)
				(justify left bottom)
				(hide yes)
			)
		)
		(property "Author" "Antmicro"
			(at 242.57 241.3 0)
			(effects
				(font
					(size 1.27 1.27)
					(thickness 0.15)
				)
				(justify left bottom)
				(hide yes)
			)
		)
		(property "License" "Apache-2.0"
			(at 242.57 243.84 0)
			(effects
				(font
					(size 1.27 1.27)
					(thickness 0.15)
				)
				(justify left bottom)
				(hide yes)
			)
		)
		(pin "1"
		)
		(pin "2"
		)
		(instances
			(project "lpddr4-test-board"
				(path ""
					(reference "D5")
					(unit 1)
				)
			)
		)
	)
	(symbol
		(lib_id "antmicroTVSDiodes:TPD2E009_SOT-9X3")
		(at 199.39 138.43 0)
		(mirror y)
		(unit 1)
		(exclude_from_sim no)
		(in_bom yes)
		(on_board yes)
		(dnp no)
		(property "Reference" "D4"
			(at 186.69 140.97 0)
			(effects
				(font
					(size 1.27 1.27)
					(thickness 0.15)
				)
				(justify right bottom)
			)
		)
		(property "Value" "TPD2E009_SOT-9X3"
			(at 184.15 148.59 0)
			(effects
				(font
					(size 1.27 1.27)
					(thickness 0.15)
				)
				(justify right bottom)
			)
		)
		(property "Footprint" "antmicro-footprints:SOT-723"
			(at 184.15 143.51 0)
			(effects
				(font
					(size 1.27 1.27)
					(thickness 0.15)
				)
				(justify left bottom)
				(hide yes)
			)
		)
		(property "Datasheet" "https://www.ti.com/lit/ds/symlink/tpd2e009.pdf?ts=1597910439511&ref_url=https%253A%252F%252Fwww.google.com%252F"
			(at 184.15 146.05 0)
			(effects
				(font
					(size 1.27 1.27)
					(thickness 0.15)
				)
				(justify left bottom)
				(hide yes)
			)
		)
		(property "Description" ""
			(at 199.39 138.43 0)
			(effects
				(font
					(size 1.27 1.27)
				)
			)
		)
		(property "MPN" "TPD2E009DRTR"
			(at 184.15 148.59 0)
			(effects
				(font
					(size 1.27 1.27)
					(thickness 0.15)
				)
				(justify left bottom)
				(hide yes)
			)
		)
		(property "Manufacturer" "Texas Instruments"
			(at 184.15 151.13 0)
			(effects
				(font
					(size 1.27 1.27)
					(thickness 0.15)
				)
				(justify left bottom)
				(hide yes)
			)
		)
		(property "Author" "Antmicro"
			(at 184.15 153.67 0)
			(effects
				(font
					(size 1.27 1.27)
					(thickness 0.15)
				)
				(justify left bottom)
				(hide yes)
			)
		)
		(property "License" "Apache-2.0"
			(at 184.15 156.21 0)
			(effects
				(font
					(size 1.27 1.27)
					(thickness 0.15)
				)
				(justify left bottom)
				(hide yes)
			)
		)
		(pin "1"
		)
		(pin "2"
		)
		(pin "3"
		)
		(instances
			(project "lpddr4-test-board"
				(path ""
					(reference "D4")
					(unit 1)
				)
			)
		)
	)
	(symbol
		(lib_id "antmicroResistors0402:R_330R_0402")
		(at 234.315 240.665 0)
		(unit 1)
		(exclude_from_sim no)
		(in_bom yes)
		(on_board yes)
		(dnp no)
		(property "Reference" "R30"
			(at 239.395 240.665 0)
			(effects
				(font
					(size 1.27 1.27)
					(thickness 0.15)
				)
				(justify left bottom)
			)
		)
		(property "Value" "R_330R_0402"
			(at 254.635 253.365 0)
			(effects
				(font
					(size 1.27 1.27)
					(thickness 0.15)
				)
				(justify left bottom)
				(hide yes)
			)
		)
		(property "Footprint" "antmicro-footprints:R_0402_1005Metric"
			(at 254.635 255.905 0)
			(effects
				(font
					(size 1.27 1.27)
					(thickness 0.15)
				)
				(justify left bottom)
				(hide yes)
			)
		)
		(property "Datasheet" "https://www.bourns.com/docs/product-datasheets/cr.pdf"
			(at 254.635 258.445 0)
			(effects
				(font
					(size 1.27 1.27)
					(thickness 0.15)
				)
				(justify left bottom)
				(hide yes)
			)
		)
		(property "Description" ""
			(at 234.315 240.665 0)
			(effects
				(font
					(size 1.27 1.27)
				)
			)
		)
		(property "Manufacturer" "Bourns"
			(at 254.635 263.525 0)
			(effects
				(font
					(size 1.27 1.27)
					(thickness 0.15)
				)
				(justify left bottom)
				(hide yes)
			)
		)
		(property "MPN" "CR0402-FX-3300GLF"
			(at 254.635 260.985 0)
			(effects
				(font
					(size 1.27 1.27)
					(thickness 0.15)
				)
				(justify left bottom)
				(hide yes)
			)
		)
		(property "Val" "330R"
			(at 229.235 240.665 0)
			(effects
				(font
					(size 1.27 1.27)
					(thickness 0.15)
				)
				(justify left bottom)
			)
		)
		(property "License" "Apache-2.0"
			(at 254.635 266.065 0)
			(effects
				(font
					(size 1.27 1.27)
					(thickness 0.15)
				)
				(justify left bottom)
				(hide yes)
			)
		)
		(property "Author" "Antmicro"
			(at 254.635 268.605 0)
			(effects
				(font
					(size 1.27 1.27)
					(thickness 0.15)
				)
				(justify left bottom)
				(hide yes)
			)
		)
		(property "Tolerance" "1%"
			(at 254.635 250.825 0)
			(effects
				(font
					(size 1.27 1.27)
				)
				(justify left bottom)
				(hide yes)
			)
		)
		(pin "1"
		)
		(pin "2"
		)
		(instances
			(project "lpddr4-test-board"
				(path ""
					(reference "R30")
					(unit 1)
				)
			)
		)
	)
	(symbol
		(lib_id "antmicroLEDIndicationDiscrete:LED_G_0603_KP-1608CGCK")
		(at 219.71 240.665 0)
		(unit 1)
		(exclude_from_sim no)
		(in_bom yes)
		(on_board yes)
		(dnp no)
		(property "Reference" "D6"
			(at 222.25 235.585 0)
			(effects
				(font
					(size 1.27 1.27)
					(thickness 0.15)
				)
				(justify left bottom)
			)
		)
		(property "Value" "LED_G_0603_KP-1608CGCK"
			(at 209.55 238.125 0)
			(effects
				(font
					(size 1.27 1.27)
					(thickness 0.15)
				)
				(justify left bottom)
			)
		)
		(property "Footprint" "antmicro-footprints:LED_0603_1608Metric_G"
			(at 242.57 250.825 0)
			(effects
				(font
					(size 1.27 1.27)
					(thickness 0.15)
				)
				(justify left bottom)
				(hide yes)
			)
		)
		(property "Datasheet" "http://www.farnell.com/datasheets/2045956.pdf"
			(at 242.57 253.365 0)
			(effects
				(font
					(size 1.27 1.27)
					(thickness 0.15)
				)
				(justify left bottom)
				(hide yes)
			)
		)
		(property "Description" ""
			(at 219.71 240.665 0)
			(effects
				(font
					(size 1.27 1.27)
				)
			)
		)
		(property "MPN" "KP-1608CGCK"
			(at 242.57 255.905 0)
			(effects
				(font
					(size 1.27 1.27)
					(thickness 0.15)
				)
				(justify left bottom)
				(hide yes)
			)
		)
		(property "Manufacturer" "Kingbright"
			(at 242.57 258.445 0)
			(effects
				(font
					(size 1.27 1.27)
					(thickness 0.15)
				)
				(justify left bottom)
				(hide yes)
			)
		)
		(property "Author" "Antmicro"
			(at 242.57 260.985 0)
			(effects
				(font
					(size 1.27 1.27)
					(thickness 0.15)
				)
				(justify left bottom)
				(hide yes)
			)
		)
		(property "License" "Apache-2.0"
			(at 242.57 263.525 0)
			(effects
				(font
					(size 1.27 1.27)
					(thickness 0.15)
				)
				(justify left bottom)
				(hide yes)
			)
		)
		(pin "1"
		)
		(pin "2"
		)
		(instances
			(project "lpddr4-test-board"
				(path ""
					(reference "D6")
					(unit 1)
				)
			)
		)
	)
	(symbol
		(lib_id "antmicroResistors0402:R_330R_0402")
		(at 170.815 260.35 0)
		(unit 1)
		(exclude_from_sim no)
		(in_bom yes)
		(on_board yes)
		(dnp no)
		(property "Reference" "R27"
			(at 175.895 260.35 0)
			(effects
				(font
					(size 1.27 1.27)
					(thickness 0.15)
				)
				(justify left bottom)
			)
		)
		(property "Value" "R_330R_0402"
			(at 191.135 273.05 0)
			(effects
				(font
					(size 1.27 1.27)
					(thickness 0.15)
				)
				(justify left bottom)
				(hide yes)
			)
		)
		(property "Footprint" "antmicro-footprints:R_0402_1005Metric"
			(at 191.135 275.59 0)
			(effects
				(font
					(size 1.27 1.27)
					(thickness 0.15)
				)
				(justify left bottom)
				(hide yes)
			)
		)
		(property "Datasheet" "https://www.bourns.com/docs/product-datasheets/cr.pdf"
			(at 191.135 278.13 0)
			(effects
				(font
					(size 1.27 1.27)
					(thickness 0.15)
				)
				(justify left bottom)
				(hide yes)
			)
		)
		(property "Description" ""
			(at 170.815 260.35 0)
			(effects
				(font
					(size 1.27 1.27)
				)
			)
		)
		(property "Manufacturer" "Bourns"
			(at 191.135 283.21 0)
			(effects
				(font
					(size 1.27 1.27)
					(thickness 0.15)
				)
				(justify left bottom)
				(hide yes)
			)
		)
		(property "MPN" "CR0402-FX-3300GLF"
			(at 191.135 280.67 0)
			(effects
				(font
					(size 1.27 1.27)
					(thickness 0.15)
				)
				(justify left bottom)
				(hide yes)
			)
		)
		(property "Val" "330R"
			(at 165.735 260.35 0)
			(effects
				(font
					(size 1.27 1.27)
					(thickness 0.15)
				)
				(justify left bottom)
			)
		)
		(property "License" "Apache-2.0"
			(at 191.135 285.75 0)
			(effects
				(font
					(size 1.27 1.27)
					(thickness 0.15)
				)
				(justify left bottom)
				(hide yes)
			)
		)
		(property "Author" "Antmicro"
			(at 191.135 288.29 0)
			(effects
				(font
					(size 1.27 1.27)
					(thickness 0.15)
				)
				(justify left bottom)
				(hide yes)
			)
		)
		(property "Tolerance" "1%"
			(at 191.135 270.51 0)
			(effects
				(font
					(size 1.27 1.27)
				)
				(justify left bottom)
				(hide yes)
			)
		)
		(pin "1"
		)
		(pin "2"
		)
		(instances
			(project "lpddr4-test-board"
				(path ""
					(reference "R27")
					(unit 1)
				)
			)
		)
	)
	(symbol
		(lib_id "antmicroLEDIndicationDiscrete:LED_G_0603_KP-1608CGCK")
		(at 156.21 260.35 0)
		(unit 1)
		(exclude_from_sim no)
		(in_bom yes)
		(on_board yes)
		(dnp no)
		(property "Reference" "D2"
			(at 158.75 255.27 0)
			(effects
				(font
					(size 1.27 1.27)
					(thickness 0.15)
				)
				(justify left bottom)
			)
		)
		(property "Value" "LED_G_0603_KP-1608CGCK"
			(at 146.05 257.81 0)
			(effects
				(font
					(size 1.27 1.27)
					(thickness 0.15)
				)
				(justify left bottom)
			)
		)
		(property "Footprint" "antmicro-footprints:LED_0603_1608Metric_G"
			(at 179.07 270.51 0)
			(effects
				(font
					(size 1.27 1.27)
					(thickness 0.15)
				)
				(justify left bottom)
				(hide yes)
			)
		)
		(property "Datasheet" "http://www.farnell.com/datasheets/2045956.pdf"
			(at 179.07 273.05 0)
			(effects
				(font
					(size 1.27 1.27)
					(thickness 0.15)
				)
				(justify left bottom)
				(hide yes)
			)
		)
		(property "Description" ""
			(at 156.21 260.35 0)
			(effects
				(font
					(size 1.27 1.27)
				)
			)
		)
		(property "MPN" "KP-1608CGCK"
			(at 179.07 275.59 0)
			(effects
				(font
					(size 1.27 1.27)
					(thickness 0.15)
				)
				(justify left bottom)
				(hide yes)
			)
		)
		(property "Manufacturer" "Kingbright"
			(at 179.07 278.13 0)
			(effects
				(font
					(size 1.27 1.27)
					(thickness 0.15)
				)
				(justify left bottom)
				(hide yes)
			)
		)
		(property "Author" "Antmicro"
			(at 179.07 280.67 0)
			(effects
				(font
					(size 1.27 1.27)
					(thickness 0.15)
				)
				(justify left bottom)
				(hide yes)
			)
		)
		(property "License" "Apache-2.0"
			(at 179.07 283.21 0)
			(effects
				(font
					(size 1.27 1.27)
					(thickness 0.15)
				)
				(justify left bottom)
				(hide yes)
			)
		)
		(pin "1"
		)
		(pin "2"
		)
		(instances
			(project "lpddr4-test-board"
				(path ""
					(reference "D2")
					(unit 1)
				)
			)
		)
	)
	(symbol
		(lib_id "antmicroResistors0402:R_22R_0402")
		(at 133.985 79.375 0)
		(unit 1)
		(exclude_from_sim no)
		(in_bom yes)
		(on_board yes)
		(dnp no)
		(property "Reference" "R21"
			(at 139.065 79.375 0)
			(effects
				(font
					(size 1.27 1.27)
					(thickness 0.15)
				)
				(justify left bottom)
			)
		)
		(property "Value" "R_22R_0402"
			(at 154.305 92.075 0)
			(effects
				(font
					(size 1.27 1.27)
					(thickness 0.15)
				)
				(justify left bottom)
				(hide yes)
			)
		)
		(property "Footprint" "antmicro-footprints:R_0402_1005Metric"
			(at 154.305 94.615 0)
			(effects
				(font
					(size 1.27 1.27)
					(thickness 0.15)
				)
				(justify left bottom)
				(hide yes)
			)
		)
		(property "Datasheet" "https://www.bourns.com/docs/product-datasheets/cr.pdf"
			(at 154.305 97.155 0)
			(effects
				(font
					(size 1.27 1.27)
					(thickness 0.15)
				)
				(justify left bottom)
				(hide yes)
			)
		)
		(property "Description" ""
			(at 133.985 79.375 0)
			(effects
				(font
					(size 1.27 1.27)
				)
			)
		)
		(property "Manufacturer" "Bourns"
			(at 154.305 102.235 0)
			(effects
				(font
					(size 1.27 1.27)
					(thickness 0.15)
				)
				(justify left bottom)
				(hide yes)
			)
		)
		(property "MPN" "CR0402-FX-22R0GLF"
			(at 154.305 99.695 0)
			(effects
				(font
					(size 1.27 1.27)
					(thickness 0.15)
				)
				(justify left bottom)
				(hide yes)
			)
		)
		(property "Val" "22R"
			(at 130.175 79.375 0)
			(effects
				(font
					(size 1.27 1.27)
					(thickness 0.15)
				)
				(justify left bottom)
			)
		)
		(property "License" "Apache-2.0"
			(at 154.305 104.775 0)
			(effects
				(font
					(size 1.27 1.27)
					(thickness 0.15)
				)
				(justify left bottom)
				(hide yes)
			)
		)
		(property "Author" "Antmicro"
			(at 154.305 107.315 0)
			(effects
				(font
					(size 1.27 1.27)
					(thickness 0.15)
				)
				(justify left bottom)
				(hide yes)
			)
		)
		(property "Tolerance" "1%"
			(at 154.305 89.535 0)
			(effects
				(font
					(size 1.27 1.27)
				)
				(justify left bottom)
				(hide yes)
			)
		)
		(pin "1"
		)
		(pin "2"
		)
		(instances
			(project "lpddr4-test-board"
				(path ""
					(reference "R21")
					(unit 1)
				)
			)
		)
	)
	(symbol
		(lib_id "antmicroResistors0402:R_22R_0402")
		(at 133.985 45.085 0)
		(unit 1)
		(exclude_from_sim no)
		(in_bom yes)
		(on_board yes)
		(dnp no)
		(property "Reference" "R13"
			(at 139.065 45.085 0)
			(effects
				(font
					(size 1.27 1.27)
					(thickness 0.15)
				)
				(justify left bottom)
			)
		)
		(property "Value" "R_22R_0402"
			(at 154.305 57.785 0)
			(effects
				(font
					(size 1.27 1.27)
					(thickness 0.15)
				)
				(justify left bottom)
				(hide yes)
			)
		)
		(property "Footprint" "antmicro-footprints:R_0402_1005Metric"
			(at 154.305 60.325 0)
			(effects
				(font
					(size 1.27 1.27)
					(thickness 0.15)
				)
				(justify left bottom)
				(hide yes)
			)
		)
		(property "Datasheet" "https://www.bourns.com/docs/product-datasheets/cr.pdf"
			(at 154.305 62.865 0)
			(effects
				(font
					(size 1.27 1.27)
					(thickness 0.15)
				)
				(justify left bottom)
				(hide yes)
			)
		)
		(property "Description" ""
			(at 133.985 45.085 0)
			(effects
				(font
					(size 1.27 1.27)
				)
			)
		)
		(property "Manufacturer" "Bourns"
			(at 154.305 67.945 0)
			(effects
				(font
					(size 1.27 1.27)
					(thickness 0.15)
				)
				(justify left bottom)
				(hide yes)
			)
		)
		(property "MPN" "CR0402-FX-22R0GLF"
			(at 154.305 65.405 0)
			(effects
				(font
					(size 1.27 1.27)
					(thickness 0.15)
				)
				(justify left bottom)
				(hide yes)
			)
		)
		(property "Val" "22R"
			(at 130.175 45.085 0)
			(effects
				(font
					(size 1.27 1.27)
					(thickness 0.15)
				)
				(justify left bottom)
			)
		)
		(property "License" "Apache-2.0"
			(at 154.305 70.485 0)
			(effects
				(font
					(size 1.27 1.27)
					(thickness 0.15)
				)
				(justify left bottom)
				(hide yes)
			)
		)
		(property "Author" "Antmicro"
			(at 154.305 73.025 0)
			(effects
				(font
					(size 1.27 1.27)
					(thickness 0.15)
				)
				(justify left bottom)
				(hide yes)
			)
		)
		(property "Tolerance" "1%"
			(at 154.305 55.245 0)
			(effects
				(font
					(size 1.27 1.27)
				)
				(justify left bottom)
				(hide yes)
			)
		)
		(pin "1"
		)
		(pin "2"
		)
		(instances
			(project "lpddr4-test-board"
				(path ""
					(reference "R13")
					(unit 1)
				)
			)
		)
	)
	(symbol
		(lib_id "antmicroResistors0402:R_22R_0402")
		(at 133.985 47.625 0)
		(unit 1)
		(exclude_from_sim no)
		(in_bom yes)
		(on_board yes)
		(dnp no)
		(property "Reference" "R14"
			(at 139.065 47.625 0)
			(effects
				(font
					(size 1.27 1.27)
					(thickness 0.15)
				)
				(justify left bottom)
			)
		)
		(property "Value" "R_22R_0402"
			(at 154.305 60.325 0)
			(effects
				(font
					(size 1.27 1.27)
					(thickness 0.15)
				)
				(justify left bottom)
				(hide yes)
			)
		)
		(property "Footprint" "antmicro-footprints:R_0402_1005Metric"
			(at 154.305 62.865 0)
			(effects
				(font
					(size 1.27 1.27)
					(thickness 0.15)
				)
				(justify left bottom)
				(hide yes)
			)
		)
		(property "Datasheet" "https://www.bourns.com/docs/product-datasheets/cr.pdf"
			(at 154.305 65.405 0)
			(effects
				(font
					(size 1.27 1.27)
					(thickness 0.15)
				)
				(justify left bottom)
				(hide yes)
			)
		)
		(property "Description" ""
			(at 133.985 47.625 0)
			(effects
				(font
					(size 1.27 1.27)
				)
			)
		)
		(property "Manufacturer" "Bourns"
			(at 154.305 70.485 0)
			(effects
				(font
					(size 1.27 1.27)
					(thickness 0.15)
				)
				(justify left bottom)
				(hide yes)
			)
		)
		(property "MPN" "CR0402-FX-22R0GLF"
			(at 154.305 67.945 0)
			(effects
				(font
					(size 1.27 1.27)
					(thickness 0.15)
				)
				(justify left bottom)
				(hide yes)
			)
		)
		(property "Val" "22R"
			(at 130.175 47.625 0)
			(effects
				(font
					(size 1.27 1.27)
					(thickness 0.15)
				)
				(justify left bottom)
			)
		)
		(property "License" "Apache-2.0"
			(at 154.305 73.025 0)
			(effects
				(font
					(size 1.27 1.27)
					(thickness 0.15)
				)
				(justify left bottom)
				(hide yes)
			)
		)
		(property "Author" "Antmicro"
			(at 154.305 75.565 0)
			(effects
				(font
					(size 1.27 1.27)
					(thickness 0.15)
				)
				(justify left bottom)
				(hide yes)
			)
		)
		(property "Tolerance" "1%"
			(at 154.305 57.785 0)
			(effects
				(font
					(size 1.27 1.27)
				)
				(justify left bottom)
				(hide yes)
			)
		)
		(pin "1"
		)
		(pin "2"
		)
		(instances
			(project "lpddr4-test-board"
				(path ""
					(reference "R14")
					(unit 1)
				)
			)
		)
	)
	(symbol
		(lib_id "antmicroResistors0402:R_22R_0402")
		(at 133.985 50.165 0)
		(unit 1)
		(exclude_from_sim no)
		(in_bom yes)
		(on_board yes)
		(dnp no)
		(property "Reference" "R15"
			(at 139.065 50.165 0)
			(effects
				(font
					(size 1.27 1.27)
					(thickness 0.15)
				)
				(justify left bottom)
			)
		)
		(property "Value" "R_22R_0402"
			(at 154.305 62.865 0)
			(effects
				(font
					(size 1.27 1.27)
					(thickness 0.15)
				)
				(justify left bottom)
				(hide yes)
			)
		)
		(property "Footprint" "antmicro-footprints:R_0402_1005Metric"
			(at 154.305 65.405 0)
			(effects
				(font
					(size 1.27 1.27)
					(thickness 0.15)
				)
				(justify left bottom)
				(hide yes)
			)
		)
		(property "Datasheet" "https://www.bourns.com/docs/product-datasheets/cr.pdf"
			(at 154.305 67.945 0)
			(effects
				(font
					(size 1.27 1.27)
					(thickness 0.15)
				)
				(justify left bottom)
				(hide yes)
			)
		)
		(property "Description" ""
			(at 133.985 50.165 0)
			(effects
				(font
					(size 1.27 1.27)
				)
			)
		)
		(property "Manufacturer" "Bourns"
			(at 154.305 73.025 0)
			(effects
				(font
					(size 1.27 1.27)
					(thickness 0.15)
				)
				(justify left bottom)
				(hide yes)
			)
		)
		(property "MPN" "CR0402-FX-22R0GLF"
			(at 154.305 70.485 0)
			(effects
				(font
					(size 1.27 1.27)
					(thickness 0.15)
				)
				(justify left bottom)
				(hide yes)
			)
		)
		(property "Val" "22R"
			(at 130.175 50.165 0)
			(effects
				(font
					(size 1.27 1.27)
					(thickness 0.15)
				)
				(justify left bottom)
			)
		)
		(property "License" "Apache-2.0"
			(at 154.305 75.565 0)
			(effects
				(font
					(size 1.27 1.27)
					(thickness 0.15)
				)
				(justify left bottom)
				(hide yes)
			)
		)
		(property "Author" "Antmicro"
			(at 154.305 78.105 0)
			(effects
				(font
					(size 1.27 1.27)
					(thickness 0.15)
				)
				(justify left bottom)
				(hide yes)
			)
		)
		(property "Tolerance" "1%"
			(at 154.305 60.325 0)
			(effects
				(font
					(size 1.27 1.27)
				)
				(justify left bottom)
				(hide yes)
			)
		)
		(pin "1"
		)
		(pin "2"
		)
		(instances
			(project "lpddr4-test-board"
				(path ""
					(reference "R15")
					(unit 1)
				)
			)
		)
	)
	(symbol
		(lib_id "antmicroResistors0402:R_22R_0402")
		(at 133.985 52.705 0)
		(unit 1)
		(exclude_from_sim no)
		(in_bom yes)
		(on_board yes)
		(dnp no)
		(property "Reference" "R16"
			(at 139.065 52.705 0)
			(effects
				(font
					(size 1.27 1.27)
					(thickness 0.15)
				)
				(justify left bottom)
			)
		)
		(property "Value" "R_22R_0402"
			(at 154.305 65.405 0)
			(effects
				(font
					(size 1.27 1.27)
					(thickness 0.15)
				)
				(justify left bottom)
				(hide yes)
			)
		)
		(property "Footprint" "antmicro-footprints:R_0402_1005Metric"
			(at 154.305 67.945 0)
			(effects
				(font
					(size 1.27 1.27)
					(thickness 0.15)
				)
				(justify left bottom)
				(hide yes)
			)
		)
		(property "Datasheet" "https://www.bourns.com/docs/product-datasheets/cr.pdf"
			(at 154.305 70.485 0)
			(effects
				(font
					(size 1.27 1.27)
					(thickness 0.15)
				)
				(justify left bottom)
				(hide yes)
			)
		)
		(property "Description" ""
			(at 133.985 52.705 0)
			(effects
				(font
					(size 1.27 1.27)
				)
			)
		)
		(property "Manufacturer" "Bourns"
			(at 154.305 75.565 0)
			(effects
				(font
					(size 1.27 1.27)
					(thickness 0.15)
				)
				(justify left bottom)
				(hide yes)
			)
		)
		(property "MPN" "CR0402-FX-22R0GLF"
			(at 154.305 73.025 0)
			(effects
				(font
					(size 1.27 1.27)
					(thickness 0.15)
				)
				(justify left bottom)
				(hide yes)
			)
		)
		(property "Val" "22R"
			(at 130.175 52.705 0)
			(effects
				(font
					(size 1.27 1.27)
					(thickness 0.15)
				)
				(justify left bottom)
			)
		)
		(property "License" "Apache-2.0"
			(at 154.305 78.105 0)
			(effects
				(font
					(size 1.27 1.27)
					(thickness 0.15)
				)
				(justify left bottom)
				(hide yes)
			)
		)
		(property "Author" "Antmicro"
			(at 154.305 80.645 0)
			(effects
				(font
					(size 1.27 1.27)
					(thickness 0.15)
				)
				(justify left bottom)
				(hide yes)
			)
		)
		(property "Tolerance" "1%"
			(at 154.305 62.865 0)
			(effects
				(font
					(size 1.27 1.27)
				)
				(justify left bottom)
				(hide yes)
			)
		)
		(pin "1"
		)
		(pin "2"
		)
		(instances
			(project "lpddr4-test-board"
				(path ""
					(reference "R16")
					(unit 1)
				)
			)
		)
	)
	(symbol
		(lib_id "antmicroTestPoints:TP_1mm_SMD")
		(at 351.79 80.01 180)
		(unit 1)
		(exclude_from_sim no)
		(in_bom yes)
		(on_board yes)
		(dnp no)
		(property "Reference" "TP2"
			(at 344.17 80.645 0)
			(effects
				(font
					(size 1.27 1.27)
					(thickness 0.15)
				)
				(justify right top)
			)
		)
		(property "Value" "TP_1mm_SMD"
			(at 336.55 72.39 0)
			(effects
				(font
					(size 1.27 1.27)
					(thickness 0.15)
				)
				(justify left bottom)
				(hide yes)
			)
		)
		(property "Footprint" "antmicro-footprints:TP_SMD_1mm"
			(at 336.55 69.85 0)
			(effects
				(font
					(size 1.27 1.27)
					(thickness 0.15)
				)
				(justify left bottom)
				(hide yes)
			)
		)
		(property "Datasheet" ""
			(at 336.55 67.31 0)
			(effects
				(font
					(size 1.27 1.27)
					(thickness 0.15)
				)
				(justify left bottom)
				(hide yes)
			)
		)
		(property "Description" ""
			(at 351.79 80.01 0)
			(effects
				(font
					(size 1.27 1.27)
				)
			)
		)
		(property "MPN" ""
			(at 351.79 80.01 0)
			(effects
				(font
					(size 1.27 1.27)
				)
				(hide yes)
			)
		)
		(property "Manufacturer" ""
			(at 351.79 80.01 0)
			(effects
				(font
					(size 1.27 1.27)
				)
				(hide yes)
			)
		)
		(property "Author" "Antmicro"
			(at 336.55 64.77 0)
			(effects
				(font
					(size 1.27 1.27)
					(thickness 0.15)
				)
				(justify left bottom)
				(hide yes)
			)
		)
		(property "License" "Apache-2.0"
			(at 336.55 62.23 0)
			(effects
				(font
					(size 1.27 1.27)
					(thickness 0.15)
				)
				(justify left bottom)
				(hide yes)
			)
		)
		(pin "1"
		)
		(instances
			(project "lpddr4-test-board"
				(path ""
					(reference "TP2")
					(unit 1)
				)
			)
		)
	)
	(symbol
		(lib_id "antmicroTestPoints:TP_1mm_SMD")
		(at 351.79 72.39 180)
		(unit 1)
		(exclude_from_sim no)
		(in_bom yes)
		(on_board yes)
		(dnp no)
		(property "Reference" "TP3"
			(at 344.17 73.025 0)
			(effects
				(font
					(size 1.27 1.27)
					(thickness 0.15)
				)
				(justify right top)
			)
		)
		(property "Value" "TP_1mm_SMD"
			(at 336.55 64.77 0)
			(effects
				(font
					(size 1.27 1.27)
					(thickness 0.15)
				)
				(justify left bottom)
				(hide yes)
			)
		)
		(property "Footprint" "antmicro-footprints:TP_SMD_1mm"
			(at 336.55 62.23 0)
			(effects
				(font
					(size 1.27 1.27)
					(thickness 0.15)
				)
				(justify left bottom)
				(hide yes)
			)
		)
		(property "Datasheet" ""
			(at 336.55 59.69 0)
			(effects
				(font
					(size 1.27 1.27)
					(thickness 0.15)
				)
				(justify left bottom)
				(hide yes)
			)
		)
		(property "Description" ""
			(at 351.79 72.39 0)
			(effects
				(font
					(size 1.27 1.27)
				)
			)
		)
		(property "MPN" ""
			(at 351.79 72.39 0)
			(effects
				(font
					(size 1.27 1.27)
				)
				(hide yes)
			)
		)
		(property "Manufacturer" ""
			(at 351.79 72.39 0)
			(effects
				(font
					(size 1.27 1.27)
				)
				(hide yes)
			)
		)
		(property "Author" "Antmicro"
			(at 336.55 57.15 0)
			(effects
				(font
					(size 1.27 1.27)
					(thickness 0.15)
				)
				(justify left bottom)
				(hide yes)
			)
		)
		(property "License" "Apache-2.0"
			(at 336.55 54.61 0)
			(effects
				(font
					(size 1.27 1.27)
					(thickness 0.15)
				)
				(justify left bottom)
				(hide yes)
			)
		)
		(pin "1"
		)
		(instances
			(project "lpddr4-test-board"
				(path ""
					(reference "TP3")
					(unit 1)
				)
			)
		)
	)
	(symbol
		(lib_id "antmicroTestPoints:TP_1mm_SMD")
		(at 351.79 85.09 180)
		(unit 1)
		(exclude_from_sim no)
		(in_bom yes)
		(on_board yes)
		(dnp no)
		(property "Reference" "TP4"
			(at 344.17 85.725 0)
			(effects
				(font
					(size 1.27 1.27)
					(thickness 0.15)
				)
				(justify right top)
			)
		)
		(property "Value" "TP_1mm_SMD"
			(at 336.55 77.47 0)
			(effects
				(font
					(size 1.27 1.27)
					(thickness 0.15)
				)
				(justify left bottom)
				(hide yes)
			)
		)
		(property "Footprint" "antmicro-footprints:TP_SMD_1mm"
			(at 336.55 74.93 0)
			(effects
				(font
					(size 1.27 1.27)
					(thickness 0.15)
				)
				(justify left bottom)
				(hide yes)
			)
		)
		(property "Datasheet" ""
			(at 336.55 72.39 0)
			(effects
				(font
					(size 1.27 1.27)
					(thickness 0.15)
				)
				(justify left bottom)
				(hide yes)
			)
		)
		(property "Description" ""
			(at 351.79 85.09 0)
			(effects
				(font
					(size 1.27 1.27)
				)
			)
		)
		(property "MPN" ""
			(at 351.79 85.09 0)
			(effects
				(font
					(size 1.27 1.27)
				)
				(hide yes)
			)
		)
		(property "Manufacturer" ""
			(at 351.79 85.09 0)
			(effects
				(font
					(size 1.27 1.27)
				)
				(hide yes)
			)
		)
		(property "Author" "Antmicro"
			(at 336.55 69.85 0)
			(effects
				(font
					(size 1.27 1.27)
					(thickness 0.15)
				)
				(justify left bottom)
				(hide yes)
			)
		)
		(property "License" "Apache-2.0"
			(at 336.55 67.31 0)
			(effects
				(font
					(size 1.27 1.27)
					(thickness 0.15)
				)
				(justify left bottom)
				(hide yes)
			)
		)
		(pin "1"
		)
		(instances
			(project "lpddr4-test-board"
				(path ""
					(reference "TP4")
					(unit 1)
				)
			)
		)
	)
	(symbol
		(lib_id "antmicroTestPoints:TP_1mm_SMD")
		(at 351.79 74.93 180)
		(unit 1)
		(exclude_from_sim no)
		(in_bom yes)
		(on_board yes)
		(dnp no)
		(property "Reference" "TP5"
			(at 347.98 74.295 0)
			(effects
				(font
					(size 1.27 1.27)
					(thickness 0.15)
				)
				(justify left bottom)
			)
		)
		(property "Value" "TP_1mm_SMD"
			(at 336.55 67.31 0)
			(effects
				(font
					(size 1.27 1.27)
					(thickness 0.15)
				)
				(justify left bottom)
				(hide yes)
			)
		)
		(property "Footprint" "antmicro-footprints:TP_SMD_1mm"
			(at 336.55 64.77 0)
			(effects
				(font
					(size 1.27 1.27)
					(thickness 0.15)
				)
				(justify left bottom)
				(hide yes)
			)
		)
		(property "Datasheet" ""
			(at 336.55 62.23 0)
			(effects
				(font
					(size 1.27 1.27)
					(thickness 0.15)
				)
				(justify left bottom)
				(hide yes)
			)
		)
		(property "Description" ""
			(at 351.79 74.93 0)
			(effects
				(font
					(size 1.27 1.27)
				)
			)
		)
		(property "MPN" ""
			(at 351.79 74.93 0)
			(effects
				(font
					(size 1.27 1.27)
				)
				(hide yes)
			)
		)
		(property "Manufacturer" ""
			(at 351.79 74.93 0)
			(effects
				(font
					(size 1.27 1.27)
				)
				(hide yes)
			)
		)
		(property "Author" "Antmicro"
			(at 336.55 59.69 0)
			(effects
				(font
					(size 1.27 1.27)
					(thickness 0.15)
				)
				(justify left bottom)
				(hide yes)
			)
		)
		(property "License" "Apache-2.0"
			(at 336.55 57.15 0)
			(effects
				(font
					(size 1.27 1.27)
					(thickness 0.15)
				)
				(justify left bottom)
				(hide yes)
			)
		)
		(pin "1"
		)
		(instances
			(project "lpddr4-test-board"
				(path ""
					(reference "TP5")
					(unit 1)
				)
			)
		)
	)
	(symbol
		(lib_id "antmicroTestPoints:TP_1mm_SMD")
		(at 351.79 92.71 180)
		(unit 1)
		(exclude_from_sim no)
		(in_bom yes)
		(on_board yes)
		(dnp no)
		(property "Reference" "TP6"
			(at 347.98 92.075 0)
			(effects
				(font
					(size 1.27 1.27)
					(thickness 0.15)
				)
				(justify left bottom)
			)
		)
		(property "Value" "TP_1mm_SMD"
			(at 336.55 85.09 0)
			(effects
				(font
					(size 1.27 1.27)
					(thickness 0.15)
				)
				(justify left bottom)
				(hide yes)
			)
		)
		(property "Footprint" "antmicro-footprints:TP_SMD_1mm"
			(at 336.55 82.55 0)
			(effects
				(font
					(size 1.27 1.27)
					(thickness 0.15)
				)
				(justify left bottom)
				(hide yes)
			)
		)
		(property "Datasheet" ""
			(at 336.55 80.01 0)
			(effects
				(font
					(size 1.27 1.27)
					(thickness 0.15)
				)
				(justify left bottom)
				(hide yes)
			)
		)
		(property "Description" ""
			(at 351.79 92.71 0)
			(effects
				(font
					(size 1.27 1.27)
				)
			)
		)
		(property "MPN" ""
			(at 351.79 92.71 0)
			(effects
				(font
					(size 1.27 1.27)
				)
				(hide yes)
			)
		)
		(property "Manufacturer" ""
			(at 351.79 92.71 0)
			(effects
				(font
					(size 1.27 1.27)
				)
				(hide yes)
			)
		)
		(property "Author" "Antmicro"
			(at 336.55 77.47 0)
			(effects
				(font
					(size 1.27 1.27)
					(thickness 0.15)
				)
				(justify left bottom)
				(hide yes)
			)
		)
		(property "License" "Apache-2.0"
			(at 336.55 74.93 0)
			(effects
				(font
					(size 1.27 1.27)
					(thickness 0.15)
				)
				(justify left bottom)
				(hide yes)
			)
		)
		(pin "1"
		)
		(instances
			(project "lpddr4-test-board"
				(path ""
					(reference "TP6")
					(unit 1)
				)
			)
		)
	)
	(symbol
		(lib_id "antmicroTVSDiodes:TPD8S009DSMR")
		(at 297.18 69.85 0)
		(mirror y)
		(unit 1)
		(exclude_from_sim no)
		(in_bom yes)
		(on_board yes)
		(dnp no)
		(property "Reference" "IC1"
			(at 288.925 63.5 0)
			(effects
				(font
					(size 1.27 1.27)
					(thickness 0.15)
				)
			)
		)
		(property "Value" "TPD8S009DSMR"
			(at 288.925 66.04 0)
			(effects
				(font
					(size 1.27 1.27)
					(thickness 0.15)
				)
			)
		)
		(property "Footprint" "antmicro-footprints:R-PDSO-N15"
			(at 266.7 77.47 0)
			(effects
				(font
					(size 1.27 1.27)
					(thickness 0.15)
				)
				(justify left bottom)
				(hide yes)
			)
		)
		(property "Datasheet" "https://www.ti.com/lit/ds/symlink/tpd8s009.pdf?ts=1679406571326&ref_url=https%253A%252F%252Fwww.ti.com%252Fproduct%252FTPD8S009%252Fpart-details%252FTPD8S009DSMR"
			(at 266.7 80.01 0)
			(effects
				(font
					(size 1.27 1.27)
					(thickness 0.15)
				)
				(justify left bottom)
				(hide yes)
			)
		)
		(property "Description" ""
			(at 297.18 69.85 0)
			(effects
				(font
					(size 1.27 1.27)
				)
			)
		)
		(property "MPN" "TPD8S009DSMR"
			(at 266.7 82.55 0)
			(effects
				(font
					(size 1.27 1.27)
					(thickness 0.15)
				)
				(justify left bottom)
				(hide yes)
			)
		)
		(property "Manufacturer" "Texas Instruments"
			(at 266.7 85.09 0)
			(effects
				(font
					(size 1.27 1.27)
					(thickness 0.15)
				)
				(justify left bottom)
				(hide yes)
			)
		)
		(property "Author" "Antmicro"
			(at 266.7 87.63 0)
			(effects
				(font
					(size 1.27 1.27)
					(thickness 0.15)
				)
				(justify left bottom)
				(hide yes)
			)
		)
		(property "License" "Apache-2.0"
			(at 266.7 90.17 0)
			(effects
				(font
					(size 1.27 1.27)
					(thickness 0.15)
				)
				(justify left bottom)
				(hide yes)
			)
		)
		(pin "1"
		)
		(pin "10"
		)
		(pin "11"
		)
		(pin "12"
		)
		(pin "13"
		)
		(pin "14"
		)
		(pin "15"
		)
		(pin "2"
		)
		(pin "3"
		)
		(pin "4"
		)
		(pin "5"
		)
		(pin "6"
		)
		(pin "7"
		)
		(pin "8"
		)
		(pin "9"
		)
		(pin "8"
		)
		(instances
			(project "lpddr4-test-board"
				(path ""
					(reference "IC1")
					(unit 1)
				)
			)
		)
	)
	(symbol
		(lib_id "antmicroResistors0402:R_0R_0402")
		(at 288.29 59.69 0)
		(mirror x)
		(unit 1)
		(exclude_from_sim no)
		(in_bom yes)
		(on_board yes)
		(dnp no)
		(property "Reference" "R39"
			(at 295.275 58.42 0)
			(effects
				(font
					(size 1.27 1.27)
					(thickness 0.15)
				)
			)
		)
		(property "Value" "R_0R_0402"
			(at 308.61 46.99 0)
			(effects
				(font
					(size 1.27 1.27)
					(thickness 0.15)
				)
				(justify left bottom)
				(hide yes)
			)
		)
		(property "Footprint" "antmicro-footprints:R_0402_1005Metric"
			(at 308.61 44.45 0)
			(effects
				(font
					(size 1.27 1.27)
					(thickness 0.15)
				)
				(justify left bottom)
				(hide yes)
			)
		)
		(property "Datasheet" "https://industrial.panasonic.com/cdbs/www-data/pdf/RDA0000/AOA0000C301.pdf"
			(at 308.61 41.91 0)
			(effects
				(font
					(size 1.27 1.27)
					(thickness 0.15)
				)
				(justify left bottom)
				(hide yes)
			)
		)
		(property "Description" ""
			(at 288.29 59.69 0)
			(effects
				(font
					(size 1.27 1.27)
				)
			)
		)
		(property "Manufacturer" "Panasonic"
			(at 308.61 36.83 0)
			(effects
				(font
					(size 1.27 1.27)
					(thickness 0.15)
				)
				(justify left bottom)
				(hide yes)
			)
		)
		(property "MPN" "ERJ2GE0R00X"
			(at 308.61 39.37 0)
			(effects
				(font
					(size 1.27 1.27)
					(thickness 0.15)
				)
				(justify left bottom)
				(hide yes)
			)
		)
		(property "Val" "0R"
			(at 287.02 58.42 0)
			(effects
				(font
					(size 1.27 1.27)
					(thickness 0.15)
				)
			)
		)
		(property "License" "Apache-2.0"
			(at 308.61 34.29 0)
			(effects
				(font
					(size 1.27 1.27)
					(thickness 0.15)
				)
				(justify left bottom)
				(hide yes)
			)
		)
		(property "Author" "Antmicro"
			(at 308.61 31.75 0)
			(effects
				(font
					(size 1.27 1.27)
					(thickness 0.15)
				)
				(justify left bottom)
				(hide yes)
			)
		)
		(property "Tolerance" "~"
			(at 308.61 49.53 0)
			(effects
				(font
					(size 1.27 1.27)
				)
				(justify left bottom)
				(hide yes)
			)
		)
		(property "Current" "1A"
			(at 308.61 29.21 0)
			(effects
				(font
					(size 1.27 1.27)
					(thickness 0.15)
				)
				(justify left bottom)
				(hide yes)
			)
		)
		(pin "1"
		)
		(pin "2"
		)
		(instances
			(project "lpddr4-test-board"
				(path ""
					(reference "R39")
					(unit 1)
				)
			)
		)
	)
	(symbol
		(lib_id "antmicroResistors0402:R_0R_0402")
		(at 288.29 57.15 0)
		(mirror x)
		(unit 1)
		(exclude_from_sim no)
		(in_bom yes)
		(on_board yes)
		(dnp no)
		(property "Reference" "R40"
			(at 295.275 55.88 0)
			(effects
				(font
					(size 1.27 1.27)
					(thickness 0.15)
				)
			)
		)
		(property "Value" "R_0R_0402"
			(at 308.61 44.45 0)
			(effects
				(font
					(size 1.27 1.27)
					(thickness 0.15)
				)
				(justify left bottom)
				(hide yes)
			)
		)
		(property "Footprint" "antmicro-footprints:R_0402_1005Metric"
			(at 308.61 41.91 0)
			(effects
				(font
					(size 1.27 1.27)
					(thickness 0.15)
				)
				(justify left bottom)
				(hide yes)
			)
		)
		(property "Datasheet" "https://industrial.panasonic.com/cdbs/www-data/pdf/RDA0000/AOA0000C301.pdf"
			(at 308.61 39.37 0)
			(effects
				(font
					(size 1.27 1.27)
					(thickness 0.15)
				)
				(justify left bottom)
				(hide yes)
			)
		)
		(property "Description" ""
			(at 288.29 57.15 0)
			(effects
				(font
					(size 1.27 1.27)
				)
			)
		)
		(property "Manufacturer" "Panasonic"
			(at 308.61 34.29 0)
			(effects
				(font
					(size 1.27 1.27)
					(thickness 0.15)
				)
				(justify left bottom)
				(hide yes)
			)
		)
		(property "MPN" "ERJ2GE0R00X"
			(at 308.61 36.83 0)
			(effects
				(font
					(size 1.27 1.27)
					(thickness 0.15)
				)
				(justify left bottom)
				(hide yes)
			)
		)
		(property "Val" "0R"
			(at 287.02 55.88 0)
			(effects
				(font
					(size 1.27 1.27)
					(thickness 0.15)
				)
			)
		)
		(property "License" "Apache-2.0"
			(at 308.61 31.75 0)
			(effects
				(font
					(size 1.27 1.27)
					(thickness 0.15)
				)
				(justify left bottom)
				(hide yes)
			)
		)
		(property "Author" "Antmicro"
			(at 308.61 29.21 0)
			(effects
				(font
					(size 1.27 1.27)
					(thickness 0.15)
				)
				(justify left bottom)
				(hide yes)
			)
		)
		(property "Tolerance" "~"
			(at 308.61 46.99 0)
			(effects
				(font
					(size 1.27 1.27)
				)
				(justify left bottom)
				(hide yes)
			)
		)
		(property "Current" "1A"
			(at 308.61 26.67 0)
			(effects
				(font
					(size 1.27 1.27)
					(thickness 0.15)
				)
				(justify left bottom)
				(hide yes)
			)
		)
		(pin "1"
		)
		(pin "2"
		)
		(instances
			(project "lpddr4-test-board"
				(path ""
					(reference "R40")
					(unit 1)
				)
			)
		)
	)
	(symbol
		(lib_id "antmicroResistors0402:R_0R_0402")
		(at 288.29 54.61 0)
		(mirror x)
		(unit 1)
		(exclude_from_sim no)
		(in_bom yes)
		(on_board yes)
		(dnp no)
		(property "Reference" "R41"
			(at 295.275 53.34 0)
			(effects
				(font
					(size 1.27 1.27)
					(thickness 0.15)
				)
			)
		)
		(property "Value" "R_0R_0402"
			(at 308.61 41.91 0)
			(effects
				(font
					(size 1.27 1.27)
					(thickness 0.15)
				)
				(justify left bottom)
				(hide yes)
			)
		)
		(property "Footprint" "antmicro-footprints:R_0402_1005Metric"
			(at 308.61 39.37 0)
			(effects
				(font
					(size 1.27 1.27)
					(thickness 0.15)
				)
				(justify left bottom)
				(hide yes)
			)
		)
		(property "Datasheet" "https://industrial.panasonic.com/cdbs/www-data/pdf/RDA0000/AOA0000C301.pdf"
			(at 308.61 36.83 0)
			(effects
				(font
					(size 1.27 1.27)
					(thickness 0.15)
				)
				(justify left bottom)
				(hide yes)
			)
		)
		(property "Description" ""
			(at 288.29 54.61 0)
			(effects
				(font
					(size 1.27 1.27)
				)
			)
		)
		(property "Manufacturer" "Panasonic"
			(at 308.61 31.75 0)
			(effects
				(font
					(size 1.27 1.27)
					(thickness 0.15)
				)
				(justify left bottom)
				(hide yes)
			)
		)
		(property "MPN" "ERJ2GE0R00X"
			(at 308.61 34.29 0)
			(effects
				(font
					(size 1.27 1.27)
					(thickness 0.15)
				)
				(justify left bottom)
				(hide yes)
			)
		)
		(property "Val" "0R"
			(at 287.02 53.34 0)
			(effects
				(font
					(size 1.27 1.27)
					(thickness 0.15)
				)
			)
		)
		(property "License" "Apache-2.0"
			(at 308.61 29.21 0)
			(effects
				(font
					(size 1.27 1.27)
					(thickness 0.15)
				)
				(justify left bottom)
				(hide yes)
			)
		)
		(property "Author" "Antmicro"
			(at 308.61 26.67 0)
			(effects
				(font
					(size 1.27 1.27)
					(thickness 0.15)
				)
				(justify left bottom)
				(hide yes)
			)
		)
		(property "Tolerance" "~"
			(at 308.61 44.45 0)
			(effects
				(font
					(size 1.27 1.27)
				)
				(justify left bottom)
				(hide yes)
			)
		)
		(property "Current" "1A"
			(at 308.61 24.13 0)
			(effects
				(font
					(size 1.27 1.27)
					(thickness 0.15)
				)
				(justify left bottom)
				(hide yes)
			)
		)
		(pin "1"
		)
		(pin "2"
		)
		(instances
			(project "lpddr4-test-board"
				(path ""
					(reference "R41")
					(unit 1)
				)
			)
		)
	)
	(symbol
		(lib_id "antmicroResistors0402:R_0R_0402")
		(at 288.29 52.07 0)
		(mirror x)
		(unit 1)
		(exclude_from_sim no)
		(in_bom yes)
		(on_board yes)
		(dnp no)
		(property "Reference" "R42"
			(at 295.275 50.8 0)
			(effects
				(font
					(size 1.27 1.27)
					(thickness 0.15)
				)
			)
		)
		(property "Value" "R_0R_0402"
			(at 308.61 39.37 0)
			(effects
				(font
					(size 1.27 1.27)
					(thickness 0.15)
				)
				(justify left bottom)
				(hide yes)
			)
		)
		(property "Footprint" "antmicro-footprints:R_0402_1005Metric"
			(at 308.61 36.83 0)
			(effects
				(font
					(size 1.27 1.27)
					(thickness 0.15)
				)
				(justify left bottom)
				(hide yes)
			)
		)
		(property "Datasheet" "https://industrial.panasonic.com/cdbs/www-data/pdf/RDA0000/AOA0000C301.pdf"
			(at 308.61 34.29 0)
			(effects
				(font
					(size 1.27 1.27)
					(thickness 0.15)
				)
				(justify left bottom)
				(hide yes)
			)
		)
		(property "Description" ""
			(at 288.29 52.07 0)
			(effects
				(font
					(size 1.27 1.27)
				)
			)
		)
		(property "Manufacturer" "Panasonic"
			(at 308.61 29.21 0)
			(effects
				(font
					(size 1.27 1.27)
					(thickness 0.15)
				)
				(justify left bottom)
				(hide yes)
			)
		)
		(property "MPN" "ERJ2GE0R00X"
			(at 308.61 31.75 0)
			(effects
				(font
					(size 1.27 1.27)
					(thickness 0.15)
				)
				(justify left bottom)
				(hide yes)
			)
		)
		(property "Val" "0R"
			(at 287.02 50.8 0)
			(effects
				(font
					(size 1.27 1.27)
					(thickness 0.15)
				)
			)
		)
		(property "License" "Apache-2.0"
			(at 308.61 26.67 0)
			(effects
				(font
					(size 1.27 1.27)
					(thickness 0.15)
				)
				(justify left bottom)
				(hide yes)
			)
		)
		(property "Author" "Antmicro"
			(at 308.61 24.13 0)
			(effects
				(font
					(size 1.27 1.27)
					(thickness 0.15)
				)
				(justify left bottom)
				(hide yes)
			)
		)
		(property "Tolerance" "~"
			(at 308.61 41.91 0)
			(effects
				(font
					(size 1.27 1.27)
				)
				(justify left bottom)
				(hide yes)
			)
		)
		(property "Current" "1A"
			(at 308.61 21.59 0)
			(effects
				(font
					(size 1.27 1.27)
					(thickness 0.15)
				)
				(justify left bottom)
				(hide yes)
			)
		)
		(pin "1"
		)
		(pin "2"
		)
		(instances
			(project "lpddr4-test-board"
				(path ""
					(reference "R42")
					(unit 1)
				)
			)
		)
	)
	(symbol
		(lib_id "antmicroResistors0402:R_0R_0402")
		(at 288.29 49.53 0)
		(mirror x)
		(unit 1)
		(exclude_from_sim no)
		(in_bom yes)
		(on_board yes)
		(dnp no)
		(property "Reference" "R43"
			(at 295.275 48.26 0)
			(effects
				(font
					(size 1.27 1.27)
					(thickness 0.15)
				)
			)
		)
		(property "Value" "R_0R_0402"
			(at 308.61 36.83 0)
			(effects
				(font
					(size 1.27 1.27)
					(thickness 0.15)
				)
				(justify left bottom)
				(hide yes)
			)
		)
		(property "Footprint" "antmicro-footprints:R_0402_1005Metric"
			(at 308.61 34.29 0)
			(effects
				(font
					(size 1.27 1.27)
					(thickness 0.15)
				)
				(justify left bottom)
				(hide yes)
			)
		)
		(property "Datasheet" "https://industrial.panasonic.com/cdbs/www-data/pdf/RDA0000/AOA0000C301.pdf"
			(at 308.61 31.75 0)
			(effects
				(font
					(size 1.27 1.27)
					(thickness 0.15)
				)
				(justify left bottom)
				(hide yes)
			)
		)
		(property "Description" ""
			(at 288.29 49.53 0)
			(effects
				(font
					(size 1.27 1.27)
				)
			)
		)
		(property "Manufacturer" "Panasonic"
			(at 308.61 26.67 0)
			(effects
				(font
					(size 1.27 1.27)
					(thickness 0.15)
				)
				(justify left bottom)
				(hide yes)
			)
		)
		(property "MPN" "ERJ2GE0R00X"
			(at 308.61 29.21 0)
			(effects
				(font
					(size 1.27 1.27)
					(thickness 0.15)
				)
				(justify left bottom)
				(hide yes)
			)
		)
		(property "Val" "0R"
			(at 287.02 48.26 0)
			(effects
				(font
					(size 1.27 1.27)
					(thickness 0.15)
				)
			)
		)
		(property "License" "Apache-2.0"
			(at 308.61 24.13 0)
			(effects
				(font
					(size 1.27 1.27)
					(thickness 0.15)
				)
				(justify left bottom)
				(hide yes)
			)
		)
		(property "Author" "Antmicro"
			(at 308.61 21.59 0)
			(effects
				(font
					(size 1.27 1.27)
					(thickness 0.15)
				)
				(justify left bottom)
				(hide yes)
			)
		)
		(property "Tolerance" "~"
			(at 308.61 39.37 0)
			(effects
				(font
					(size 1.27 1.27)
				)
				(justify left bottom)
				(hide yes)
			)
		)
		(property "Current" "1A"
			(at 308.61 19.05 0)
			(effects
				(font
					(size 1.27 1.27)
					(thickness 0.15)
				)
				(justify left bottom)
				(hide yes)
			)
		)
		(pin "1"
		)
		(pin "2"
		)
		(instances
			(project "lpddr4-test-board"
				(path ""
					(reference "R43")
					(unit 1)
				)
			)
		)
	)
	(symbol
		(lib_id "antmicroResistors0402:R_0R_0402")
		(at 288.29 46.99 0)
		(mirror x)
		(unit 1)
		(exclude_from_sim no)
		(in_bom yes)
		(on_board yes)
		(dnp no)
		(property "Reference" "R44"
			(at 295.275 45.72 0)
			(effects
				(font
					(size 1.27 1.27)
					(thickness 0.15)
				)
			)
		)
		(property "Value" "R_0R_0402"
			(at 308.61 34.29 0)
			(effects
				(font
					(size 1.27 1.27)
					(thickness 0.15)
				)
				(justify left bottom)
				(hide yes)
			)
		)
		(property "Footprint" "antmicro-footprints:R_0402_1005Metric"
			(at 308.61 31.75 0)
			(effects
				(font
					(size 1.27 1.27)
					(thickness 0.15)
				)
				(justify left bottom)
				(hide yes)
			)
		)
		(property "Datasheet" "https://industrial.panasonic.com/cdbs/www-data/pdf/RDA0000/AOA0000C301.pdf"
			(at 308.61 29.21 0)
			(effects
				(font
					(size 1.27 1.27)
					(thickness 0.15)
				)
				(justify left bottom)
				(hide yes)
			)
		)
		(property "Description" ""
			(at 288.29 46.99 0)
			(effects
				(font
					(size 1.27 1.27)
				)
			)
		)
		(property "Manufacturer" "Panasonic"
			(at 308.61 24.13 0)
			(effects
				(font
					(size 1.27 1.27)
					(thickness 0.15)
				)
				(justify left bottom)
				(hide yes)
			)
		)
		(property "MPN" "ERJ2GE0R00X"
			(at 308.61 26.67 0)
			(effects
				(font
					(size 1.27 1.27)
					(thickness 0.15)
				)
				(justify left bottom)
				(hide yes)
			)
		)
		(property "Val" "0R"
			(at 287.02 45.72 0)
			(effects
				(font
					(size 1.27 1.27)
					(thickness 0.15)
				)
			)
		)
		(property "License" "Apache-2.0"
			(at 308.61 21.59 0)
			(effects
				(font
					(size 1.27 1.27)
					(thickness 0.15)
				)
				(justify left bottom)
				(hide yes)
			)
		)
		(property "Author" "Antmicro"
			(at 308.61 19.05 0)
			(effects
				(font
					(size 1.27 1.27)
					(thickness 0.15)
				)
				(justify left bottom)
				(hide yes)
			)
		)
		(property "Tolerance" "~"
			(at 308.61 36.83 0)
			(effects
				(font
					(size 1.27 1.27)
				)
				(justify left bottom)
				(hide yes)
			)
		)
		(property "Current" "1A"
			(at 308.61 16.51 0)
			(effects
				(font
					(size 1.27 1.27)
					(thickness 0.15)
				)
				(justify left bottom)
				(hide yes)
			)
		)
		(pin "1"
		)
		(pin "2"
		)
		(instances
			(project "lpddr4-test-board"
				(path ""
					(reference "R44")
					(unit 1)
				)
			)
		)
	)
	(symbol
		(lib_id "antmicroResistors0402:R_0R_0402")
		(at 288.29 44.45 0)
		(mirror x)
		(unit 1)
		(exclude_from_sim no)
		(in_bom yes)
		(on_board yes)
		(dnp no)
		(property "Reference" "R45"
			(at 295.275 43.18 0)
			(effects
				(font
					(size 1.27 1.27)
					(thickness 0.15)
				)
			)
		)
		(property "Value" "R_0R_0402"
			(at 308.61 31.75 0)
			(effects
				(font
					(size 1.27 1.27)
					(thickness 0.15)
				)
				(justify left bottom)
				(hide yes)
			)
		)
		(property "Footprint" "antmicro-footprints:R_0402_1005Metric"
			(at 308.61 29.21 0)
			(effects
				(font
					(size 1.27 1.27)
					(thickness 0.15)
				)
				(justify left bottom)
				(hide yes)
			)
		)
		(property "Datasheet" "https://industrial.panasonic.com/cdbs/www-data/pdf/RDA0000/AOA0000C301.pdf"
			(at 308.61 26.67 0)
			(effects
				(font
					(size 1.27 1.27)
					(thickness 0.15)
				)
				(justify left bottom)
				(hide yes)
			)
		)
		(property "Description" ""
			(at 288.29 44.45 0)
			(effects
				(font
					(size 1.27 1.27)
				)
			)
		)
		(property "Manufacturer" "Panasonic"
			(at 308.61 21.59 0)
			(effects
				(font
					(size 1.27 1.27)
					(thickness 0.15)
				)
				(justify left bottom)
				(hide yes)
			)
		)
		(property "MPN" "ERJ2GE0R00X"
			(at 308.61 24.13 0)
			(effects
				(font
					(size 1.27 1.27)
					(thickness 0.15)
				)
				(justify left bottom)
				(hide yes)
			)
		)
		(property "Val" "0R"
			(at 287.02 43.18 0)
			(effects
				(font
					(size 1.27 1.27)
					(thickness 0.15)
				)
			)
		)
		(property "License" "Apache-2.0"
			(at 308.61 19.05 0)
			(effects
				(font
					(size 1.27 1.27)
					(thickness 0.15)
				)
				(justify left bottom)
				(hide yes)
			)
		)
		(property "Author" "Antmicro"
			(at 308.61 16.51 0)
			(effects
				(font
					(size 1.27 1.27)
					(thickness 0.15)
				)
				(justify left bottom)
				(hide yes)
			)
		)
		(property "Tolerance" "~"
			(at 308.61 34.29 0)
			(effects
				(font
					(size 1.27 1.27)
				)
				(justify left bottom)
				(hide yes)
			)
		)
		(property "Current" "1A"
			(at 308.61 13.97 0)
			(effects
				(font
					(size 1.27 1.27)
					(thickness 0.15)
				)
				(justify left bottom)
				(hide yes)
			)
		)
		(pin "1"
		)
		(pin "2"
		)
		(instances
			(project "lpddr4-test-board"
				(path ""
					(reference "R45")
					(unit 1)
				)
			)
		)
	)
	(symbol
		(lib_id "antmicroResistors0402:R_0R_0402")
		(at 288.29 41.91 0)
		(mirror x)
		(unit 1)
		(exclude_from_sim no)
		(in_bom yes)
		(on_board yes)
		(dnp no)
		(property "Reference" "R46"
			(at 295.275 40.64 0)
			(effects
				(font
					(size 1.27 1.27)
					(thickness 0.15)
				)
			)
		)
		(property "Value" "R_0R_0402"
			(at 308.61 29.21 0)
			(effects
				(font
					(size 1.27 1.27)
					(thickness 0.15)
				)
				(justify left bottom)
				(hide yes)
			)
		)
		(property "Footprint" "antmicro-footprints:R_0402_1005Metric"
			(at 308.61 26.67 0)
			(effects
				(font
					(size 1.27 1.27)
					(thickness 0.15)
				)
				(justify left bottom)
				(hide yes)
			)
		)
		(property "Datasheet" "https://industrial.panasonic.com/cdbs/www-data/pdf/RDA0000/AOA0000C301.pdf"
			(at 308.61 24.13 0)
			(effects
				(font
					(size 1.27 1.27)
					(thickness 0.15)
				)
				(justify left bottom)
				(hide yes)
			)
		)
		(property "Description" ""
			(at 288.29 41.91 0)
			(effects
				(font
					(size 1.27 1.27)
				)
			)
		)
		(property "Manufacturer" "Panasonic"
			(at 308.61 19.05 0)
			(effects
				(font
					(size 1.27 1.27)
					(thickness 0.15)
				)
				(justify left bottom)
				(hide yes)
			)
		)
		(property "MPN" "ERJ2GE0R00X"
			(at 308.61 21.59 0)
			(effects
				(font
					(size 1.27 1.27)
					(thickness 0.15)
				)
				(justify left bottom)
				(hide yes)
			)
		)
		(property "Val" "0R"
			(at 287.02 40.64 0)
			(effects
				(font
					(size 1.27 1.27)
					(thickness 0.15)
				)
			)
		)
		(property "License" "Apache-2.0"
			(at 308.61 16.51 0)
			(effects
				(font
					(size 1.27 1.27)
					(thickness 0.15)
				)
				(justify left bottom)
				(hide yes)
			)
		)
		(property "Author" "Antmicro"
			(at 308.61 13.97 0)
			(effects
				(font
					(size 1.27 1.27)
					(thickness 0.15)
				)
				(justify left bottom)
				(hide yes)
			)
		)
		(property "Tolerance" "~"
			(at 308.61 31.75 0)
			(effects
				(font
					(size 1.27 1.27)
				)
				(justify left bottom)
				(hide yes)
			)
		)
		(property "Current" "1A"
			(at 308.61 11.43 0)
			(effects
				(font
					(size 1.27 1.27)
					(thickness 0.15)
				)
				(justify left bottom)
				(hide yes)
			)
		)
		(pin "1"
		)
		(pin "2"
		)
		(instances
			(project "lpddr4-test-board"
				(path ""
					(reference "R46")
					(unit 1)
				)
			)
		)
	)
	(symbol
		(lib_id "antmicroMemoryConnectorsPCCardSockets:MicroSD_1140084168")
		(at 339.09 166.37 0)
		(unit 1)
		(exclude_from_sim no)
		(in_bom yes)
		(on_board yes)
		(dnp no)
		(property "Reference" "J3"
			(at 341.63 160.655 0)
			(effects
				(font
					(size 1.27 1.27)
					(thickness 0.15)
				)
				(justify left bottom)
			)
		)
		(property "Value" "MicroSD_1140084168"
			(at 341.63 163.195 0)
			(effects
				(font
					(size 1.27 1.27)
					(thickness 0.15)
				)
				(justify left bottom)
			)
		)
		(property "Footprint" "antmicro-footprints:MicroSD_Amphenol_1140084168"
			(at 377.19 175.26 0)
			(effects
				(font
					(size 1.27 1.27)
					(thickness 0.15)
				)
				(justify left bottom)
				(hide yes)
			)
		)
		(property "Datasheet" "https://cdn.amphenol-cs.com/media/wysiwyg/files/documentation/datasheet/inputoutput/io_micro_sdcard.pdf"
			(at 377.19 177.8 0)
			(effects
				(font
					(size 1.27 1.27)
					(thickness 0.15)
				)
				(justify left bottom)
				(hide yes)
			)
		)
		(property "Description" ""
			(at 339.09 166.37 0)
			(effects
				(font
					(size 1.27 1.27)
				)
			)
		)
		(property "MPN" "1140084168"
			(at 377.19 180.34 0)
			(effects
				(font
					(size 1.27 1.27)
					(thickness 0.15)
				)
				(justify left bottom)
				(hide yes)
			)
		)
		(property "Manufacturer" "Amphenol"
			(at 377.19 182.88 0)
			(effects
				(font
					(size 1.27 1.27)
					(thickness 0.15)
				)
				(justify left bottom)
				(hide yes)
			)
		)
		(property "Author" "Antmicro"
			(at 377.19 185.42 0)
			(effects
				(font
					(size 1.27 1.27)
					(thickness 0.15)
				)
				(justify left bottom)
				(hide yes)
			)
		)
		(property "License" "Apache-2.0"
			(at 377.19 187.96 0)
			(effects
				(font
					(size 1.27 1.27)
					(thickness 0.15)
				)
				(justify left bottom)
				(hide yes)
			)
		)
		(pin "1"
		)
		(pin "10"
		)
		(pin "2"
		)
		(pin "3"
		)
		(pin "4"
		)
		(pin "5"
		)
		(pin "6"
		)
		(pin "7"
		)
		(pin "8"
		)
		(pin "9"
		)
		(pin "SH"
		)
		(instances
			(project "lpddr4-test-board"
				(path ""
					(reference "J3")
					(unit 1)
				)
			)
		)
	)
	(symbol
		(lib_id "antmicroResistors0402:R_20k_0402")
		(at 336.55 153.67 270)
		(unit 1)
		(exclude_from_sim no)
		(in_bom yes)
		(on_board yes)
		(dnp no)
		(property "Reference" "R38"
			(at 337.82 156.21 90)
			(effects
				(font
					(size 1.27 1.27)
					(thickness 0.15)
				)
				(justify left bottom)
			)
		)
		(property "Value" "R_20k_0402"
			(at 323.85 173.99 0)
			(effects
				(font
					(size 1.27 1.27)
					(thickness 0.15)
				)
				(justify left bottom)
				(hide yes)
			)
		)
		(property "Footprint" "antmicro-footprints:R_0402_1005Metric"
			(at 321.31 173.99 0)
			(effects
				(font
					(size 1.27 1.27)
					(thickness 0.15)
				)
				(justify left bottom)
				(hide yes)
			)
		)
		(property "Datasheet" "https://www.bourns.com/docs/product-datasheets/cr.pdf"
			(at 318.77 173.99 0)
			(effects
				(font
					(size 1.27 1.27)
					(thickness 0.15)
				)
				(justify left bottom)
				(hide yes)
			)
		)
		(property "Description" ""
			(at 336.55 153.67 0)
			(effects
				(font
					(size 1.27 1.27)
				)
			)
		)
		(property "Manufacturer" "Bourns"
			(at 313.69 173.99 0)
			(effects
				(font
					(size 1.27 1.27)
					(thickness 0.15)
				)
				(justify left bottom)
				(hide yes)
			)
		)
		(property "MPN" "CR0402-FX-2002GLF"
			(at 316.23 173.99 0)
			(effects
				(font
					(size 1.27 1.27)
					(thickness 0.15)
				)
				(justify left bottom)
				(hide yes)
			)
		)
		(property "Val" "20k"
			(at 337.82 158.115 90)
			(effects
				(font
					(size 1.27 1.27)
					(thickness 0.15)
				)
				(justify left bottom)
			)
		)
		(property "License" "Apache-2.0"
			(at 311.15 173.99 0)
			(effects
				(font
					(size 1.27 1.27)
					(thickness 0.15)
				)
				(justify left bottom)
				(hide yes)
			)
		)
		(property "Author" "Antmicro"
			(at 308.61 173.99 0)
			(effects
				(font
					(size 1.27 1.27)
					(thickness 0.15)
				)
				(justify left bottom)
				(hide yes)
			)
		)
		(property "Tolerance" "1%"
			(at 326.39 173.99 0)
			(effects
				(font
					(size 1.27 1.27)
				)
				(justify left bottom)
				(hide yes)
			)
		)
		(pin "1"
		)
		(pin "2"
		)
		(instances
			(project "lpddr4-test-board"
				(path ""
					(reference "R38")
					(unit 1)
				)
			)
		)
	)
	(symbol
		(lib_id "antmicroResistors0402:R_20k_0402")
		(at 330.835 158.75 270)
		(unit 1)
		(exclude_from_sim no)
		(in_bom yes)
		(on_board yes)
		(dnp no)
		(property "Reference" "R37"
			(at 332.105 161.29 90)
			(effects
				(font
					(size 1.27 1.27)
					(thickness 0.15)
				)
				(justify left bottom)
			)
		)
		(property "Value" "R_20k_0402"
			(at 318.135 179.07 0)
			(effects
				(font
					(size 1.27 1.27)
					(thickness 0.15)
				)
				(justify left bottom)
				(hide yes)
			)
		)
		(property "Footprint" "antmicro-footprints:R_0402_1005Metric"
			(at 315.595 179.07 0)
			(effects
				(font
					(size 1.27 1.27)
					(thickness 0.15)
				)
				(justify left bottom)
				(hide yes)
			)
		)
		(property "Datasheet" "https://www.bourns.com/docs/product-datasheets/cr.pdf"
			(at 313.055 179.07 0)
			(effects
				(font
					(size 1.27 1.27)
					(thickness 0.15)
				)
				(justify left bottom)
				(hide yes)
			)
		)
		(property "Description" ""
			(at 330.835 158.75 0)
			(effects
				(font
					(size 1.27 1.27)
				)
			)
		)
		(property "Manufacturer" "Bourns"
			(at 307.975 179.07 0)
			(effects
				(font
					(size 1.27 1.27)
					(thickness 0.15)
				)
				(justify left bottom)
				(hide yes)
			)
		)
		(property "MPN" "CR0402-FX-2002GLF"
			(at 310.515 179.07 0)
			(effects
				(font
					(size 1.27 1.27)
					(thickness 0.15)
				)
				(justify left bottom)
				(hide yes)
			)
		)
		(property "Val" "20k"
			(at 332.105 163.195 90)
			(effects
				(font
					(size 1.27 1.27)
					(thickness 0.15)
				)
				(justify left bottom)
			)
		)
		(property "License" "Apache-2.0"
			(at 305.435 179.07 0)
			(effects
				(font
					(size 1.27 1.27)
					(thickness 0.15)
				)
				(justify left bottom)
				(hide yes)
			)
		)
		(property "Author" "Antmicro"
			(at 302.895 179.07 0)
			(effects
				(font
					(size 1.27 1.27)
					(thickness 0.15)
				)
				(justify left bottom)
				(hide yes)
			)
		)
		(property "Tolerance" "1%"
			(at 320.675 179.07 0)
			(effects
				(font
					(size 1.27 1.27)
				)
				(justify left bottom)
				(hide yes)
			)
		)
		(pin "1"
		)
		(pin "2"
		)
		(instances
			(project "lpddr4-test-board"
				(path ""
					(reference "R37")
					(unit 1)
				)
			)
		)
	)
	(symbol
		(lib_id "antmicroResistors0402:R_20k_0402")
		(at 325.12 153.67 270)
		(unit 1)
		(exclude_from_sim no)
		(in_bom yes)
		(on_board yes)
		(dnp no)
		(property "Reference" "R35"
			(at 326.39 156.21 90)
			(effects
				(font
					(size 1.27 1.27)
					(thickness 0.15)
				)
				(justify left bottom)
			)
		)
		(property "Value" "R_20k_0402"
			(at 312.42 173.99 0)
			(effects
				(font
					(size 1.27 1.27)
					(thickness 0.15)
				)
				(justify left bottom)
				(hide yes)
			)
		)
		(property "Footprint" "antmicro-footprints:R_0402_1005Metric"
			(at 309.88 173.99 0)
			(effects
				(font
					(size 1.27 1.27)
					(thickness 0.15)
				)
				(justify left bottom)
				(hide yes)
			)
		)
		(property "Datasheet" "https://www.bourns.com/docs/product-datasheets/cr.pdf"
			(at 307.34 173.99 0)
			(effects
				(font
					(size 1.27 1.27)
					(thickness 0.15)
				)
				(justify left bottom)
				(hide yes)
			)
		)
		(property "Description" ""
			(at 325.12 153.67 0)
			(effects
				(font
					(size 1.27 1.27)
				)
			)
		)
		(property "Manufacturer" "Bourns"
			(at 302.26 173.99 0)
			(effects
				(font
					(size 1.27 1.27)
					(thickness 0.15)
				)
				(justify left bottom)
				(hide yes)
			)
		)
		(property "MPN" "CR0402-FX-2002GLF"
			(at 304.8 173.99 0)
			(effects
				(font
					(size 1.27 1.27)
					(thickness 0.15)
				)
				(justify left bottom)
				(hide yes)
			)
		)
		(property "Val" "20k"
			(at 326.39 158.115 90)
			(effects
				(font
					(size 1.27 1.27)
					(thickness 0.15)
				)
				(justify left bottom)
			)
		)
		(property "License" "Apache-2.0"
			(at 299.72 173.99 0)
			(effects
				(font
					(size 1.27 1.27)
					(thickness 0.15)
				)
				(justify left bottom)
				(hide yes)
			)
		)
		(property "Author" "Antmicro"
			(at 297.18 173.99 0)
			(effects
				(font
					(size 1.27 1.27)
					(thickness 0.15)
				)
				(justify left bottom)
				(hide yes)
			)
		)
		(property "Tolerance" "1%"
			(at 314.96 173.99 0)
			(effects
				(font
					(size 1.27 1.27)
				)
				(justify left bottom)
				(hide yes)
			)
		)
		(pin "1"
		)
		(pin "2"
		)
		(instances
			(project "lpddr4-test-board"
				(path ""
					(reference "R35")
					(unit 1)
				)
			)
		)
	)
	(symbol
		(lib_id "antmicroResistors0402:R_20k_0402")
		(at 319.405 158.75 270)
		(unit 1)
		(exclude_from_sim no)
		(in_bom yes)
		(on_board yes)
		(dnp no)
		(property "Reference" "R34"
			(at 320.675 161.29 90)
			(effects
				(font
					(size 1.27 1.27)
					(thickness 0.15)
				)
				(justify left bottom)
			)
		)
		(property "Value" "R_20k_0402"
			(at 306.705 179.07 0)
			(effects
				(font
					(size 1.27 1.27)
					(thickness 0.15)
				)
				(justify left bottom)
				(hide yes)
			)
		)
		(property "Footprint" "antmicro-footprints:R_0402_1005Metric"
			(at 304.165 179.07 0)
			(effects
				(font
					(size 1.27 1.27)
					(thickness 0.15)
				)
				(justify left bottom)
				(hide yes)
			)
		)
		(property "Datasheet" "https://www.bourns.com/docs/product-datasheets/cr.pdf"
			(at 301.625 179.07 0)
			(effects
				(font
					(size 1.27 1.27)
					(thickness 0.15)
				)
				(justify left bottom)
				(hide yes)
			)
		)
		(property "Description" ""
			(at 319.405 158.75 0)
			(effects
				(font
					(size 1.27 1.27)
				)
			)
		)
		(property "Manufacturer" "Bourns"
			(at 296.545 179.07 0)
			(effects
				(font
					(size 1.27 1.27)
					(thickness 0.15)
				)
				(justify left bottom)
				(hide yes)
			)
		)
		(property "MPN" "CR0402-FX-2002GLF"
			(at 299.085 179.07 0)
			(effects
				(font
					(size 1.27 1.27)
					(thickness 0.15)
				)
				(justify left bottom)
				(hide yes)
			)
		)
		(property "Val" "20k"
			(at 320.675 163.195 90)
			(effects
				(font
					(size 1.27 1.27)
					(thickness 0.15)
				)
				(justify left bottom)
			)
		)
		(property "License" "Apache-2.0"
			(at 294.005 179.07 0)
			(effects
				(font
					(size 1.27 1.27)
					(thickness 0.15)
				)
				(justify left bottom)
				(hide yes)
			)
		)
		(property "Author" "Antmicro"
			(at 291.465 179.07 0)
			(effects
				(font
					(size 1.27 1.27)
					(thickness 0.15)
				)
				(justify left bottom)
				(hide yes)
			)
		)
		(property "Tolerance" "1%"
			(at 309.245 179.07 0)
			(effects
				(font
					(size 1.27 1.27)
				)
				(justify left bottom)
				(hide yes)
			)
		)
		(pin "1"
		)
		(pin "2"
		)
		(instances
			(project "lpddr4-test-board"
				(path ""
					(reference "R34")
					(unit 1)
				)
			)
		)
	)
	(symbol
		(lib_id "antmicroResistors0402:R_20k_0402")
		(at 313.69 153.67 270)
		(unit 1)
		(exclude_from_sim no)
		(in_bom yes)
		(on_board yes)
		(dnp no)
		(property "Reference" "R33"
			(at 314.96 156.21 90)
			(effects
				(font
					(size 1.27 1.27)
					(thickness 0.15)
				)
				(justify left bottom)
			)
		)
		(property "Value" "R_20k_0402"
			(at 300.99 173.99 0)
			(effects
				(font
					(size 1.27 1.27)
					(thickness 0.15)
				)
				(justify left bottom)
				(hide yes)
			)
		)
		(property "Footprint" "antmicro-footprints:R_0402_1005Metric"
			(at 298.45 173.99 0)
			(effects
				(font
					(size 1.27 1.27)
					(thickness 0.15)
				)
				(justify left bottom)
				(hide yes)
			)
		)
		(property "Datasheet" "https://www.bourns.com/docs/product-datasheets/cr.pdf"
			(at 295.91 173.99 0)
			(effects
				(font
					(size 1.27 1.27)
					(thickness 0.15)
				)
				(justify left bottom)
				(hide yes)
			)
		)
		(property "Description" ""
			(at 313.69 153.67 0)
			(effects
				(font
					(size 1.27 1.27)
				)
			)
		)
		(property "Manufacturer" "Bourns"
			(at 290.83 173.99 0)
			(effects
				(font
					(size 1.27 1.27)
					(thickness 0.15)
				)
				(justify left bottom)
				(hide yes)
			)
		)
		(property "MPN" "CR0402-FX-2002GLF"
			(at 293.37 173.99 0)
			(effects
				(font
					(size 1.27 1.27)
					(thickness 0.15)
				)
				(justify left bottom)
				(hide yes)
			)
		)
		(property "Val" "20k"
			(at 314.96 158.115 90)
			(effects
				(font
					(size 1.27 1.27)
					(thickness 0.15)
				)
				(justify left bottom)
			)
		)
		(property "License" "Apache-2.0"
			(at 288.29 173.99 0)
			(effects
				(font
					(size 1.27 1.27)
					(thickness 0.15)
				)
				(justify left bottom)
				(hide yes)
			)
		)
		(property "Author" "Antmicro"
			(at 285.75 173.99 0)
			(effects
				(font
					(size 1.27 1.27)
					(thickness 0.15)
				)
				(justify left bottom)
				(hide yes)
			)
		)
		(property "Tolerance" "1%"
			(at 303.53 173.99 0)
			(effects
				(font
					(size 1.27 1.27)
				)
				(justify left bottom)
				(hide yes)
			)
		)
		(pin "1"
		)
		(pin "2"
		)
		(instances
			(project "lpddr4-test-board"
				(path ""
					(reference "R33")
					(unit 1)
				)
			)
		)
	)
	(symbol
		(lib_id "antmicroResistors0402:R_20k_0402")
		(at 307.34 158.75 270)
		(unit 1)
		(exclude_from_sim no)
		(in_bom yes)
		(on_board yes)
		(dnp no)
		(property "Reference" "R32"
			(at 308.61 161.29 90)
			(effects
				(font
					(size 1.27 1.27)
					(thickness 0.15)
				)
				(justify left bottom)
			)
		)
		(property "Value" "R_20k_0402"
			(at 294.64 179.07 0)
			(effects
				(font
					(size 1.27 1.27)
					(thickness 0.15)
				)
				(justify left bottom)
				(hide yes)
			)
		)
		(property "Footprint" "antmicro-footprints:R_0402_1005Metric"
			(at 292.1 179.07 0)
			(effects
				(font
					(size 1.27 1.27)
					(thickness 0.15)
				)
				(justify left bottom)
				(hide yes)
			)
		)
		(property "Datasheet" "https://www.bourns.com/docs/product-datasheets/cr.pdf"
			(at 289.56 179.07 0)
			(effects
				(font
					(size 1.27 1.27)
					(thickness 0.15)
				)
				(justify left bottom)
				(hide yes)
			)
		)
		(property "Description" ""
			(at 307.34 158.75 0)
			(effects
				(font
					(size 1.27 1.27)
				)
			)
		)
		(property "Manufacturer" "Bourns"
			(at 284.48 179.07 0)
			(effects
				(font
					(size 1.27 1.27)
					(thickness 0.15)
				)
				(justify left bottom)
				(hide yes)
			)
		)
		(property "MPN" "CR0402-FX-2002GLF"
			(at 287.02 179.07 0)
			(effects
				(font
					(size 1.27 1.27)
					(thickness 0.15)
				)
				(justify left bottom)
				(hide yes)
			)
		)
		(property "Val" "20k"
			(at 308.61 163.195 90)
			(effects
				(font
					(size 1.27 1.27)
					(thickness 0.15)
				)
				(justify left bottom)
			)
		)
		(property "License" "Apache-2.0"
			(at 281.94 179.07 0)
			(effects
				(font
					(size 1.27 1.27)
					(thickness 0.15)
				)
				(justify left bottom)
				(hide yes)
			)
		)
		(property "Author" "Antmicro"
			(at 279.4 179.07 0)
			(effects
				(font
					(size 1.27 1.27)
					(thickness 0.15)
				)
				(justify left bottom)
				(hide yes)
			)
		)
		(property "Tolerance" "1%"
			(at 297.18 179.07 0)
			(effects
				(font
					(size 1.27 1.27)
				)
				(justify left bottom)
				(hide yes)
			)
		)
		(pin "1"
		)
		(pin "2"
		)
		(instances
			(project "lpddr4-test-board"
				(path ""
					(reference "R32")
					(unit 1)
				)
			)
		)
	)
	(symbol
		(lib_id "antmicroResistors0402:R_20k_0402")
		(at 301.625 153.67 270)
		(unit 1)
		(exclude_from_sim no)
		(in_bom yes)
		(on_board yes)
		(dnp no)
		(property "Reference" "R31"
			(at 302.895 156.21 90)
			(effects
				(font
					(size 1.27 1.27)
					(thickness 0.15)
				)
				(justify left bottom)
			)
		)
		(property "Value" "R_20k_0402"
			(at 288.925 173.99 0)
			(effects
				(font
					(size 1.27 1.27)
					(thickness 0.15)
				)
				(justify left bottom)
				(hide yes)
			)
		)
		(property "Footprint" "antmicro-footprints:R_0402_1005Metric"
			(at 286.385 173.99 0)
			(effects
				(font
					(size 1.27 1.27)
					(thickness 0.15)
				)
				(justify left bottom)
				(hide yes)
			)
		)
		(property "Datasheet" "https://www.bourns.com/docs/product-datasheets/cr.pdf"
			(at 283.845 173.99 0)
			(effects
				(font
					(size 1.27 1.27)
					(thickness 0.15)
				)
				(justify left bottom)
				(hide yes)
			)
		)
		(property "Description" ""
			(at 301.625 153.67 0)
			(effects
				(font
					(size 1.27 1.27)
				)
			)
		)
		(property "Manufacturer" "Bourns"
			(at 278.765 173.99 0)
			(effects
				(font
					(size 1.27 1.27)
					(thickness 0.15)
				)
				(justify left bottom)
				(hide yes)
			)
		)
		(property "MPN" "CR0402-FX-2002GLF"
			(at 281.305 173.99 0)
			(effects
				(font
					(size 1.27 1.27)
					(thickness 0.15)
				)
				(justify left bottom)
				(hide yes)
			)
		)
		(property "Val" "20k"
			(at 302.895 158.115 90)
			(effects
				(font
					(size 1.27 1.27)
					(thickness 0.15)
				)
				(justify left bottom)
			)
		)
		(property "License" "Apache-2.0"
			(at 276.225 173.99 0)
			(effects
				(font
					(size 1.27 1.27)
					(thickness 0.15)
				)
				(justify left bottom)
				(hide yes)
			)
		)
		(property "Author" "Antmicro"
			(at 273.685 173.99 0)
			(effects
				(font
					(size 1.27 1.27)
					(thickness 0.15)
				)
				(justify left bottom)
				(hide yes)
			)
		)
		(property "Tolerance" "1%"
			(at 291.465 173.99 0)
			(effects
				(font
					(size 1.27 1.27)
				)
				(justify left bottom)
				(hide yes)
			)
		)
		(pin "1"
		)
		(pin "2"
		)
		(instances
			(project "lpddr4-test-board"
				(path ""
					(reference "R31")
					(unit 1)
				)
			)
		)
	)
	(symbol
		(lib_id "antmicroResistors0402:R_220R_0402")
		(at 322.58 186.69 0)
		(unit 1)
		(exclude_from_sim no)
		(in_bom yes)
		(on_board yes)
		(dnp no)
		(property "Reference" "R36"
			(at 327.66 186.69 0)
			(effects
				(font
					(size 1.27 1.27)
					(thickness 0.15)
				)
				(justify left bottom)
			)
		)
		(property "Value" "R_220R_0402"
			(at 342.9 199.39 0)
			(effects
				(font
					(size 1.27 1.27)
					(thickness 0.15)
				)
				(justify left bottom)
				(hide yes)
			)
		)
		(property "Footprint" "antmicro-footprints:R_0402_1005Metric"
			(at 342.9 201.93 0)
			(effects
				(font
					(size 1.27 1.27)
					(thickness 0.15)
				)
				(justify left bottom)
				(hide yes)
			)
		)
		(property "Datasheet" "https://www.bourns.com/docs/product-datasheets/cr.pdf"
			(at 342.9 204.47 0)
			(effects
				(font
					(size 1.27 1.27)
					(thickness 0.15)
				)
				(justify left bottom)
				(hide yes)
			)
		)
		(property "Description" ""
			(at 322.58 186.69 0)
			(effects
				(font
					(size 1.27 1.27)
				)
			)
		)
		(property "Manufacturer" "Bourns"
			(at 342.9 209.55 0)
			(effects
				(font
					(size 1.27 1.27)
					(thickness 0.15)
				)
				(justify left bottom)
				(hide yes)
			)
		)
		(property "MPN" "CR0402-FX-2200GLF"
			(at 342.9 207.01 0)
			(effects
				(font
					(size 1.27 1.27)
					(thickness 0.15)
				)
				(justify left bottom)
				(hide yes)
			)
		)
		(property "Val" "220R"
			(at 317.5 186.69 0)
			(effects
				(font
					(size 1.27 1.27)
					(thickness 0.15)
				)
				(justify left bottom)
			)
		)
		(property "License" "Apache-2.0"
			(at 342.9 212.09 0)
			(effects
				(font
					(size 1.27 1.27)
					(thickness 0.15)
				)
				(justify left bottom)
				(hide yes)
			)
		)
		(property "Author" "Antmicro"
			(at 342.9 214.63 0)
			(effects
				(font
					(size 1.27 1.27)
					(thickness 0.15)
				)
				(justify left bottom)
				(hide yes)
			)
		)
		(property "Tolerance" "1%"
			(at 342.9 196.85 0)
			(effects
				(font
					(size 1.27 1.27)
				)
				(justify left bottom)
				(hide yes)
			)
		)
		(pin "1"
		)
		(pin "2"
		)
		(instances
			(project "lpddr4-test-board"
				(path ""
					(reference "R36")
					(unit 1)
				)
			)
		)
	)
	(symbol
		(lib_id "antmicropower:GND")
		(at 336.55 191.77 0)
		(unit 1)
		(exclude_from_sim no)
		(in_bom yes)
		(on_board yes)
		(dnp no)
		(property "Reference" "#PWR042"
			(at 345.44 194.31 0)
			(effects
				(font
					(size 1.27 1.27)
					(thickness 0.15)
				)
				(justify left bottom)
				(hide yes)
			)
		)
		(property "Value" "GND"
			(at 334.645 196.215 0)
			(effects
				(font
					(size 1.27 1.27)
					(thickness 0.15)
				)
				(justify left bottom)
			)
		)
		(property "Footprint" ""
			(at 345.44 199.39 0)
			(effects
				(font
					(size 1.27 1.27)
					(thickness 0.15)
				)
				(justify left bottom)
				(hide yes)
			)
		)
		(property "Datasheet" ""
			(at 345.44 204.47 0)
			(effects
				(font
					(size 1.27 1.27)
					(thickness 0.15)
				)
				(justify left bottom)
				(hide yes)
			)
		)
		(property "Description" ""
			(at 336.55 191.77 0)
			(effects
				(font
					(size 1.27 1.27)
				)
			)
		)
		(property "Author" "Antmicro"
			(at 345.44 199.39 0)
			(effects
				(font
					(size 1.27 1.27)
					(thickness 0.15)
				)
				(justify left bottom)
				(hide yes)
			)
		)
		(property "License" "Apache-2.0"
			(at 345.44 201.93 0)
			(effects
				(font
					(size 1.27 1.27)
					(thickness 0.15)
				)
				(justify left bottom)
				(hide yes)
			)
		)
		(pin "1"
		)
		(instances
			(project "lpddr4-test-board"
				(path ""
					(reference "#PWR042")
					(unit 1)
				)
			)
		)
	)
	(symbol
		(lib_id "antmicroTransistorsFETsMOSFETsSingle:BSS138PW")
		(at 189.23 228.6 90)
		(unit 1)
		(exclude_from_sim no)
		(in_bom yes)
		(on_board yes)
		(dnp no)
		(property "Reference" "Q1"
			(at 185.42 215.9 90)
			(effects
				(font
					(size 1.27 1.27)
					(thickness 0.15)
				)
				(justify right top)
			)
		)
		(property "Value" "BSS138PW"
			(at 182.245 218.44 90)
			(effects
				(font
					(size 1.27 1.27)
					(thickness 0.15)
				)
				(justify right top)
			)
		)
		(property "Footprint" "antmicro-footprints:SC70-3"
			(at 200.66 205.74 0)
			(effects
				(font
					(size 1.27 1.27)
					(thickness 0.15)
				)
				(justify left bottom)
				(hide yes)
			)
		)
		(property "Datasheet" "https://assets.nexperia.com/documents/data-sheet/BSS138PW.pdf"
			(at 203.2 205.74 0)
			(effects
				(font
					(size 1.27 1.27)
					(thickness 0.15)
				)
				(justify left bottom)
				(hide yes)
			)
		)
		(property "Description" ""
			(at 189.23 228.6 0)
			(effects
				(font
					(size 1.27 1.27)
				)
			)
		)
		(property "MPN" "BSS138PW"
			(at 205.74 205.74 0)
			(effects
				(font
					(size 1.27 1.27)
					(thickness 0.15)
				)
				(justify left bottom)
				(hide yes)
			)
		)
		(property "Manufacturer" "Nexperia"
			(at 208.28 205.74 0)
			(effects
				(font
					(size 1.27 1.27)
					(thickness 0.15)
				)
				(justify left bottom)
				(hide yes)
			)
		)
		(property "Author" "Antmicro"
			(at 210.82 205.74 0)
			(effects
				(font
					(size 1.27 1.27)
					(thickness 0.15)
				)
				(justify left bottom)
				(hide yes)
			)
		)
		(property "License" "Apache-2.0"
			(at 213.36 205.74 0)
			(effects
				(font
					(size 1.27 1.27)
					(thickness 0.15)
				)
				(justify left bottom)
				(hide yes)
			)
		)
		(pin "1"
		)
		(pin "2"
		)
		(pin "3"
		)
		(instances
			(project "lpddr4-test-board"
				(path ""
					(reference "Q1")
					(unit 1)
				)
			)
		)
	)
	(symbol
		(lib_id "antmicroTransistorsFETsMOSFETsSingle:BSS138PW")
		(at 189.865 248.285 90)
		(unit 1)
		(exclude_from_sim no)
		(in_bom yes)
		(on_board yes)
		(dnp no)
		(property "Reference" "Q3"
			(at 186.055 235.585 90)
			(effects
				(font
					(size 1.27 1.27)
					(thickness 0.15)
				)
				(justify right top)
			)
		)
		(property "Value" "BSS138PW"
			(at 182.88 238.125 90)
			(effects
				(font
					(size 1.27 1.27)
					(thickness 0.15)
				)
				(justify right top)
			)
		)
		(property "Footprint" "antmicro-footprints:SC70-3"
			(at 201.295 225.425 0)
			(effects
				(font
					(size 1.27 1.27)
					(thickness 0.15)
				)
				(justify left bottom)
				(hide yes)
			)
		)
		(property "Datasheet" "https://assets.nexperia.com/documents/data-sheet/BSS138PW.pdf"
			(at 203.835 225.425 0)
			(effects
				(font
					(size 1.27 1.27)
					(thickness 0.15)
				)
				(justify left bottom)
				(hide yes)
			)
		)
		(property "Description" ""
			(at 189.865 248.285 0)
			(effects
				(font
					(size 1.27 1.27)
				)
			)
		)
		(property "MPN" "BSS138PW"
			(at 206.375 225.425 0)
			(effects
				(font
					(size 1.27 1.27)
					(thickness 0.15)
				)
				(justify left bottom)
				(hide yes)
			)
		)
		(property "Manufacturer" "Nexperia"
			(at 208.915 225.425 0)
			(effects
				(font
					(size 1.27 1.27)
					(thickness 0.15)
				)
				(justify left bottom)
				(hide yes)
			)
		)
		(property "Author" "Antmicro"
			(at 211.455 225.425 0)
			(effects
				(font
					(size 1.27 1.27)
					(thickness 0.15)
				)
				(justify left bottom)
				(hide yes)
			)
		)
		(property "License" "Apache-2.0"
			(at 213.995 225.425 0)
			(effects
				(font
					(size 1.27 1.27)
					(thickness 0.15)
				)
				(justify left bottom)
				(hide yes)
			)
		)
		(pin "1"
		)
		(pin "2"
		)
		(pin "3"
		)
		(instances
			(project "lpddr4-test-board"
				(path ""
					(reference "Q3")
					(unit 1)
				)
			)
		)
	)
	(symbol
		(lib_id "antmicroTransistorsFETsMOSFETsSingle:BSS138PW")
		(at 252.73 228.6 90)
		(unit 1)
		(exclude_from_sim no)
		(in_bom yes)
		(on_board yes)
		(dnp no)
		(property "Reference" "Q4"
			(at 248.92 215.9 90)
			(effects
				(font
					(size 1.27 1.27)
					(thickness 0.15)
				)
				(justify right top)
			)
		)
		(property "Value" "BSS138PW"
			(at 245.745 218.44 90)
			(effects
				(font
					(size 1.27 1.27)
					(thickness 0.15)
				)
				(justify right top)
			)
		)
		(property "Footprint" "antmicro-footprints:SC70-3"
			(at 264.16 205.74 0)
			(effects
				(font
					(size 1.27 1.27)
					(thickness 0.15)
				)
				(justify left bottom)
				(hide yes)
			)
		)
		(property "Datasheet" "https://assets.nexperia.com/documents/data-sheet/BSS138PW.pdf"
			(at 266.7 205.74 0)
			(effects
				(font
					(size 1.27 1.27)
					(thickness 0.15)
				)
				(justify left bottom)
				(hide yes)
			)
		)
		(property "Description" ""
			(at 252.73 228.6 0)
			(effects
				(font
					(size 1.27 1.27)
				)
			)
		)
		(property "MPN" "BSS138PW"
			(at 269.24 205.74 0)
			(effects
				(font
					(size 1.27 1.27)
					(thickness 0.15)
				)
				(justify left bottom)
				(hide yes)
			)
		)
		(property "Manufacturer" "Nexperia"
			(at 271.78 205.74 0)
			(effects
				(font
					(size 1.27 1.27)
					(thickness 0.15)
				)
				(justify left bottom)
				(hide yes)
			)
		)
		(property "Author" "Antmicro"
			(at 274.32 205.74 0)
			(effects
				(font
					(size 1.27 1.27)
					(thickness 0.15)
				)
				(justify left bottom)
				(hide yes)
			)
		)
		(property "License" "Apache-2.0"
			(at 276.86 205.74 0)
			(effects
				(font
					(size 1.27 1.27)
					(thickness 0.15)
				)
				(justify left bottom)
				(hide yes)
			)
		)
		(pin "1"
		)
		(pin "2"
		)
		(pin "3"
		)
		(instances
			(project "lpddr4-test-board"
				(path ""
					(reference "Q4")
					(unit 1)
				)
			)
		)
	)
	(symbol
		(lib_id "antmicroTransistorsFETsMOSFETsSingle:BSS138PW")
		(at 252.73 248.285 90)
		(unit 1)
		(exclude_from_sim no)
		(in_bom yes)
		(on_board yes)
		(dnp no)
		(property "Reference" "Q5"
			(at 248.92 235.585 90)
			(effects
				(font
					(size 1.27 1.27)
					(thickness 0.15)
				)
				(justify right top)
			)
		)
		(property "Value" "BSS138PW"
			(at 245.745 238.125 90)
			(effects
				(font
					(size 1.27 1.27)
					(thickness 0.15)
				)
				(justify right top)
			)
		)
		(property "Footprint" "antmicro-footprints:SC70-3"
			(at 264.16 225.425 0)
			(effects
				(font
					(size 1.27 1.27)
					(thickness 0.15)
				)
				(justify left bottom)
				(hide yes)
			)
		)
		(property "Datasheet" "https://assets.nexperia.com/documents/data-sheet/BSS138PW.pdf"
			(at 266.7 225.425 0)
			(effects
				(font
					(size 1.27 1.27)
					(thickness 0.15)
				)
				(justify left bottom)
				(hide yes)
			)
		)
		(property "Description" ""
			(at 252.73 248.285 0)
			(effects
				(font
					(size 1.27 1.27)
				)
			)
		)
		(property "MPN" "BSS138PW"
			(at 269.24 225.425 0)
			(effects
				(font
					(size 1.27 1.27)
					(thickness 0.15)
				)
				(justify left bottom)
				(hide yes)
			)
		)
		(property "Manufacturer" "Nexperia"
			(at 271.78 225.425 0)
			(effects
				(font
					(size 1.27 1.27)
					(thickness 0.15)
				)
				(justify left bottom)
				(hide yes)
			)
		)
		(property "Author" "Antmicro"
			(at 274.32 225.425 0)
			(effects
				(font
					(size 1.27 1.27)
					(thickness 0.15)
				)
				(justify left bottom)
				(hide yes)
			)
		)
		(property "License" "Apache-2.0"
			(at 276.86 225.425 0)
			(effects
				(font
					(size 1.27 1.27)
					(thickness 0.15)
				)
				(justify left bottom)
				(hide yes)
			)
		)
		(pin "1"
		)
		(pin "2"
		)
		(pin "3"
		)
		(instances
			(project "lpddr4-test-board"
				(path ""
					(reference "Q5")
					(unit 1)
				)
			)
		)
	)
	(symbol
		(lib_id "antmicroTransistorsFETsMOSFETsSingle:BSS138PW")
		(at 189.23 267.97 90)
		(unit 1)
		(exclude_from_sim no)
		(in_bom yes)
		(on_board yes)
		(dnp no)
		(property "Reference" "Q2"
			(at 185.42 255.27 90)
			(effects
				(font
					(size 1.27 1.27)
					(thickness 0.15)
				)
				(justify right top)
			)
		)
		(property "Value" "BSS138PW"
			(at 182.245 257.81 90)
			(effects
				(font
					(size 1.27 1.27)
					(thickness 0.15)
				)
				(justify right top)
			)
		)
		(property "Footprint" "antmicro-footprints:SC70-3"
			(at 200.66 245.11 0)
			(effects
				(font
					(size 1.27 1.27)
					(thickness 0.15)
				)
				(justify left bottom)
				(hide yes)
			)
		)
		(property "Datasheet" "https://assets.nexperia.com/documents/data-sheet/BSS138PW.pdf"
			(at 203.2 245.11 0)
			(effects
				(font
					(size 1.27 1.27)
					(thickness 0.15)
				)
				(justify left bottom)
				(hide yes)
			)
		)
		(property "Description" ""
			(at 189.23 267.97 0)
			(effects
				(font
					(size 1.27 1.27)
				)
			)
		)
		(property "MPN" "BSS138PW"
			(at 205.74 245.11 0)
			(effects
				(font
					(size 1.27 1.27)
					(thickness 0.15)
				)
				(justify left bottom)
				(hide yes)
			)
		)
		(property "Manufacturer" "Nexperia"
			(at 208.28 245.11 0)
			(effects
				(font
					(size 1.27 1.27)
					(thickness 0.15)
				)
				(justify left bottom)
				(hide yes)
			)
		)
		(property "Author" "Antmicro"
			(at 210.82 245.11 0)
			(effects
				(font
					(size 1.27 1.27)
					(thickness 0.15)
				)
				(justify left bottom)
				(hide yes)
			)
		)
		(property "License" "Apache-2.0"
			(at 213.36 245.11 0)
			(effects
				(font
					(size 1.27 1.27)
					(thickness 0.15)
				)
				(justify left bottom)
				(hide yes)
			)
		)
		(pin "1"
		)
		(pin "2"
		)
		(pin "3"
		)
		(instances
			(project "lpddr4-test-board"
				(path ""
					(reference "Q2")
					(unit 1)
				)
			)
		)
	)
	(symbol
		(lib_id "antmicroCapacitors0603:C_1u_0603")
		(at 370.84 182.88 90)
		(unit 1)
		(exclude_from_sim no)
		(in_bom yes)
		(on_board yes)
		(dnp no)
		(property "Reference" "C21"
			(at 371.475 179.705 90)
			(effects
				(font
					(size 1.27 1.27)
					(thickness 0.15)
				)
				(justify right top)
			)
		)
		(property "Value" "C_1u_0603"
			(at 381 162.56 0)
			(effects
				(font
					(size 1.27 1.27)
					(thickness 0.15)
				)
				(justify left bottom)
				(hide yes)
			)
		)
		(property "Footprint" "antmicro-footprints:C_0603_1608Metric"
			(at 383.54 162.56 0)
			(effects
				(font
					(size 1.27 1.27)
					(thickness 0.15)
				)
				(justify left bottom)
				(hide yes)
			)
		)
		(property "Datasheet" " "
			(at 386.08 162.56 0)
			(effects
				(font
					(size 1.27 1.27)
					(thickness 0.15)
				)
				(justify left bottom)
				(hide yes)
			)
		)
		(property "Description" ""
			(at 370.84 182.88 0)
			(effects
				(font
					(size 1.27 1.27)
				)
			)
		)
		(property "Manufacturer" "Walsin"
			(at 391.16 162.56 0)
			(effects
				(font
					(size 1.27 1.27)
					(thickness 0.15)
				)
				(justify left bottom)
				(hide yes)
			)
		)
		(property "MPN" "0603YD105KAT2A"
			(at 388.62 162.56 0)
			(effects
				(font
					(size 1.27 1.27)
					(thickness 0.15)
				)
				(justify left bottom)
				(hide yes)
			)
		)
		(property "Val" "1u"
			(at 371.475 183.515 90)
			(effects
				(font
					(size 1.27 1.27)
					(thickness 0.15)
				)
				(justify right top)
			)
		)
		(property "License" "Apache-2.0"
			(at 393.7 162.56 0)
			(effects
				(font
					(size 1.27 1.27)
					(thickness 0.15)
				)
				(justify left bottom)
				(hide yes)
			)
		)
		(property "Author" "Antmicro"
			(at 396.24 162.56 0)
			(effects
				(font
					(size 1.27 1.27)
					(thickness 0.15)
				)
				(justify left bottom)
				(hide yes)
			)
		)
		(property "Voltage" ""
			(at 398.78 162.56 0)
			(effects
				(font
					(size 1.27 1.27)
				)
				(justify left bottom)
				(hide yes)
			)
		)
		(property "Dielectric" ""
			(at 401.32 162.56 0)
			(effects
				(font
					(size 1.27 1.27)
				)
				(justify left bottom)
				(hide yes)
			)
		)
		(pin "1"
		)
		(pin "2"
		)
		(instances
			(project "lpddr4-test-board"
				(path ""
					(reference "C21")
					(unit 1)
				)
			)
		)
	)
	(symbol
		(lib_id "antmicroResonators:Resonator_12MHz_ABM8G")
		(at 70.485 107.315 0)
		(unit 1)
		(exclude_from_sim no)
		(in_bom yes)
		(on_board yes)
		(dnp no)
		(property "Reference" "Y1"
			(at 74.295 101.6 0)
			(effects
				(font
					(size 1.27 1.27)
					(thickness 0.15)
				)
			)
		)
		(property "Value" "Oscillator_SMD_12MHz_KX-7"
			(at 74.295 102.235 0)
			(effects
				(font
					(size 1.27 1.27)
					(thickness 0.15)
				)
				(hide yes)
			)
		)
		(property "Footprint" "antmicro-footprints:Resonator_SMD_Abracon_ABM8G_3.2x2.5mm"
			(at 85.725 122.555 0)
			(effects
				(font
					(size 1.27 1.27)
					(thickness 0.15)
				)
				(justify left bottom)
				(hide yes)
			)
		)
		(property "Datasheet" "https://abracon.com/Resonators/ABM8G.pdf"
			(at 85.725 125.095 0)
			(effects
				(font
					(size 1.27 1.27)
					(thickness 0.15)
				)
				(justify left bottom)
				(hide yes)
			)
		)
		(property "Description" ""
			(at 70.485 107.315 0)
			(effects
				(font
					(size 1.27 1.27)
				)
			)
		)
		(property "MPN" "ABM8G-12.000MHZ-18-D2Y-T"
			(at 85.725 114.935 0)
			(effects
				(font
					(size 1.27 1.27)
					(thickness 0.15)
				)
				(justify left bottom)
				(hide yes)
			)
		)
		(property "Manufacturer" "Abracon"
			(at 85.725 127.635 0)
			(effects
				(font
					(size 1.27 1.27)
					(thickness 0.15)
				)
				(justify left bottom)
				(hide yes)
			)
		)
		(property "Val" "12 MHz"
			(at 71.12 104.14 0)
			(effects
				(font
					(size 1.27 1.27)
					(thickness 0.15)
				)
				(justify left bottom)
			)
		)
		(property "Author" "Antmicro"
			(at 85.725 130.175 0)
			(effects
				(font
					(size 1.27 1.27)
					(thickness 0.15)
				)
				(justify left bottom)
				(hide yes)
			)
		)
		(property "License" "Apache-2.0"
			(at 85.725 132.715 0)
			(effects
				(font
					(size 1.27 1.27)
					(thickness 0.15)
				)
				(justify left bottom)
				(hide yes)
			)
		)
		(pin "1"
		)
		(pin "2"
		)
		(pin "3"
		)
		(pin "4"
		)
		(instances
			(project "lpddr4-test-board"
				(path ""
					(reference "Y1")
					(unit 1)
				)
			)
		)
	)
	(symbol
		(lib_id "antmicroVideoConnectors:HDMI-A_WE_685119134923")
		(at 353.06 41.91 0)
		(unit 1)
		(exclude_from_sim no)
		(in_bom yes)
		(on_board yes)
		(dnp no)
		(property "Reference" "J2"
			(at 367.03 35.56 0)
			(effects
				(font
					(size 1.27 1.27)
					(thickness 0.15)
				)
			)
		)
		(property "Value" "HDMI-A_685119134923"
			(at 388.62 46.99 0)
			(effects
				(font
					(size 1.27 1.27)
					(thickness 0.15)
				)
				(justify left bottom)
				(hide yes)
			)
		)
		(property "Footprint" "antmicro-footprints:HDMI-A_Receptacle_WE_685119134923"
			(at 388.62 49.53 0)
			(effects
				(font
					(size 1.27 1.27)
					(thickness 0.15)
				)
				(justify left bottom)
				(hide yes)
			)
		)
		(property "Datasheet" "https://www.we-online.com/components/products/datasheet/685119134923.pdf"
			(at 388.62 52.07 0)
			(effects
				(font
					(size 1.27 1.27)
					(thickness 0.15)
				)
				(justify left bottom)
				(hide yes)
			)
		)
		(property "Description" ""
			(at 353.06 41.91 0)
			(effects
				(font
					(size 1.27 1.27)
				)
			)
		)
		(property "MPN" "685119134923"
			(at 359.41 38.1 0)
			(effects
				(font
					(size 1.27 1.27)
					(thickness 0.15)
				)
				(justify left bottom)
			)
		)
		(property "Manufacturer" "Würth Elektronik"
			(at 388.62 57.15 0)
			(effects
				(font
					(size 1.27 1.27)
					(thickness 0.15)
				)
				(justify left bottom)
				(hide yes)
			)
		)
		(property "Author" "Antmicro"
			(at 388.62 59.69 0)
			(effects
				(font
					(size 1.27 1.27)
					(thickness 0.15)
				)
				(justify left bottom)
				(hide yes)
			)
		)
		(property "License" "Apache-2.0"
			(at 388.62 62.23 0)
			(effects
				(font
					(size 1.27 1.27)
					(thickness 0.15)
				)
				(justify left bottom)
				(hide yes)
			)
		)
		(pin "1"
		)
		(pin "10"
		)
		(pin "11"
		)
		(pin "12"
		)
		(pin "13"
		)
		(pin "14"
		)
		(pin "15"
		)
		(pin "16"
		)
		(pin "17"
		)
		(pin "18"
		)
		(pin "19"
		)
		(pin "2"
		)
		(pin "3"
		)
		(pin "4"
		)
		(pin "5"
		)
		(pin "6"
		)
		(pin "7"
		)
		(pin "8"
		)
		(pin "9"
		)
		(pin "SH"
		)
		(instances
			(project "lpddr4-test-board"
				(path ""
					(reference "J2")
					(unit 1)
				)
			)
		)
	)
	(symbol
		(lib_id "antmicropower:GND")
		(at 83.185 139.065 0)
		(unit 1)
		(exclude_from_sim no)
		(in_bom yes)
		(on_board yes)
		(dnp no)
		(property "Reference" "#PWR0123"
			(at 92.075 141.605 0)
			(effects
				(font
					(size 1.27 1.27)
					(thickness 0.15)
				)
				(justify left bottom)
				(hide yes)
			)
		)
		(property "Value" "GND"
			(at 81.28 143.51 0)
			(effects
				(font
					(size 1.27 1.27)
					(thickness 0.15)
				)
				(justify left bottom)
			)
		)
		(property "Footprint" ""
			(at 92.075 146.685 0)
			(effects
				(font
					(size 1.27 1.27)
					(thickness 0.15)
				)
				(justify left bottom)
				(hide yes)
			)
		)
		(property "Datasheet" ""
			(at 92.075 151.765 0)
			(effects
				(font
					(size 1.27 1.27)
					(thickness 0.15)
				)
				(justify left bottom)
				(hide yes)
			)
		)
		(property "Description" ""
			(at 83.185 139.065 0)
			(effects
				(font
					(size 1.27 1.27)
				)
			)
		)
		(property "Author" "Antmicro"
			(at 92.075 146.685 0)
			(effects
				(font
					(size 1.27 1.27)
					(thickness 0.15)
				)
				(justify left bottom)
				(hide yes)
			)
		)
		(property "License" "Apache-2.0"
			(at 92.075 149.225 0)
			(effects
				(font
					(size 1.27 1.27)
					(thickness 0.15)
				)
				(justify left bottom)
				(hide yes)
			)
		)
		(pin "1"
		)
		(instances
			(project "lpddr4-test-board"
				(path ""
					(reference "#PWR0123")
					(unit 1)
				)
			)
		)
	)
	(symbol
		(lib_id "antmicropower:GND")
		(at 83.185 116.205 0)
		(unit 1)
		(exclude_from_sim no)
		(in_bom yes)
		(on_board yes)
		(dnp no)
		(property "Reference" "#PWR0109"
			(at 92.075 118.745 0)
			(effects
				(font
					(size 1.27 1.27)
					(thickness 0.15)
				)
				(justify left bottom)
				(hide yes)
			)
		)
		(property "Value" "GND"
			(at 81.28 120.65 0)
			(effects
				(font
					(size 1.27 1.27)
					(thickness 0.15)
				)
				(justify left bottom)
			)
		)
		(property "Footprint" ""
			(at 92.075 123.825 0)
			(effects
				(font
					(size 1.27 1.27)
					(thickness 0.15)
				)
				(justify left bottom)
				(hide yes)
			)
		)
		(property "Datasheet" ""
			(at 92.075 128.905 0)
			(effects
				(font
					(size 1.27 1.27)
					(thickness 0.15)
				)
				(justify left bottom)
				(hide yes)
			)
		)
		(property "Description" ""
			(at 83.185 116.205 0)
			(effects
				(font
					(size 1.27 1.27)
				)
			)
		)
		(property "Author" "Antmicro"
			(at 92.075 123.825 0)
			(effects
				(font
					(size 1.27 1.27)
					(thickness 0.15)
				)
				(justify left bottom)
				(hide yes)
			)
		)
		(property "License" "Apache-2.0"
			(at 92.075 126.365 0)
			(effects
				(font
					(size 1.27 1.27)
					(thickness 0.15)
				)
				(justify left bottom)
				(hide yes)
			)
		)
		(pin "1"
		)
		(instances
			(project "lpddr4-test-board"
				(path ""
					(reference "#PWR0109")
					(unit 1)
				)
			)
		)
	)
	(symbol
		(lib_id "antmicropower:GND")
		(at 46.355 91.44 0)
		(unit 1)
		(exclude_from_sim no)
		(in_bom yes)
		(on_board yes)
		(dnp no)
		(property "Reference" "#PWR0113"
			(at 55.245 93.98 0)
			(effects
				(font
					(size 1.27 1.27)
					(thickness 0.15)
				)
				(justify left bottom)
				(hide yes)
			)
		)
		(property "Value" "GND"
			(at 44.45 95.885 0)
			(effects
				(font
					(size 1.27 1.27)
					(thickness 0.15)
				)
				(justify left bottom)
			)
		)
		(property "Footprint" ""
			(at 55.245 99.06 0)
			(effects
				(font
					(size 1.27 1.27)
					(thickness 0.15)
				)
				(justify left bottom)
				(hide yes)
			)
		)
		(property "Datasheet" ""
			(at 55.245 104.14 0)
			(effects
				(font
					(size 1.27 1.27)
					(thickness 0.15)
				)
				(justify left bottom)
				(hide yes)
			)
		)
		(property "Description" ""
			(at 46.355 91.44 0)
			(effects
				(font
					(size 1.27 1.27)
				)
			)
		)
		(property "Author" "Antmicro"
			(at 55.245 99.06 0)
			(effects
				(font
					(size 1.27 1.27)
					(thickness 0.15)
				)
				(justify left bottom)
				(hide yes)
			)
		)
		(property "License" "Apache-2.0"
			(at 55.245 101.6 0)
			(effects
				(font
					(size 1.27 1.27)
					(thickness 0.15)
				)
				(justify left bottom)
				(hide yes)
			)
		)
		(pin "1"
		)
		(instances
			(project "lpddr4-test-board"
				(path ""
					(reference "#PWR0113")
					(unit 1)
				)
			)
		)
	)
	(symbol
		(lib_id "antmicroInterfaceControllers:FT4232H_VQFN")
		(at 88.265 45.085 0)
		(unit 1)
		(exclude_from_sim no)
		(in_bom yes)
		(on_board yes)
		(dnp no)
		(property "Reference" "U4"
			(at 90.805 39.37 0)
			(effects
				(font
					(size 1.27 1.27)
					(thickness 0.15)
				)
				(justify left bottom)
			)
		)
		(property "Value" "FT4232H_VQFN"
			(at 90.805 41.91 0)
			(effects
				(font
					(size 1.27 1.27)
					(thickness 0.15)
				)
				(justify left bottom)
			)
		)
		(property "Footprint" "antmicro-footprints:QFN-56-1EP_8x8mm_P0.5mm"
			(at 144.145 52.705 0)
			(effects
				(font
					(size 1.27 1.27)
					(thickness 0.15)
				)
				(justify left bottom)
				(hide yes)
			)
		)
		(property "Datasheet" "https://www.ftdichip.com/Support/Documents/DataSheets/ICs/DS_FT4232H.pdf"
			(at 144.145 55.245 0)
			(effects
				(font
					(size 1.27 1.27)
					(thickness 0.15)
				)
				(justify left bottom)
				(hide yes)
			)
		)
		(property "Description" ""
			(at 88.265 45.085 0)
			(effects
				(font
					(size 1.27 1.27)
				)
			)
		)
		(property "Manufacturer" "FTDI Chip"
			(at 144.145 57.785 0)
			(effects
				(font
					(size 1.27 1.27)
					(thickness 0.15)
				)
				(justify left bottom)
				(hide yes)
			)
		)
		(property "MPN" "FT4232H-56Q-REEL"
			(at 144.145 60.325 0)
			(effects
				(font
					(size 1.27 1.27)
					(thickness 0.15)
				)
				(justify left bottom)
				(hide yes)
			)
		)
		(property "Author" "Antmicro"
			(at 144.145 62.865 0)
			(effects
				(font
					(size 1.27 1.27)
					(thickness 0.15)
				)
				(justify left bottom)
				(hide yes)
			)
		)
		(property "License" "Apache-2.0"
			(at 144.145 65.405 0)
			(effects
				(font
					(size 1.27 1.27)
					(thickness 0.15)
				)
				(justify left bottom)
				(hide yes)
			)
		)
		(pin "1"
		)
		(pin "10"
		)
		(pin "11"
		)
		(pin "12"
		)
		(pin "13"
		)
		(pin "14"
		)
		(pin "15"
		)
		(pin "16"
		)
		(pin "17"
		)
		(pin "18"
		)
		(pin "19"
		)
		(pin "2"
		)
		(pin "20"
		)
		(pin "21"
		)
		(pin "22"
		)
		(pin "23"
		)
		(pin "24"
		)
		(pin "25"
		)
		(pin "26"
		)
		(pin "27"
		)
		(pin "28"
		)
		(pin "29"
		)
		(pin "3"
		)
		(pin "30"
		)
		(pin "31"
		)
		(pin "32"
		)
		(pin "33"
		)
		(pin "34"
		)
		(pin "35"
		)
		(pin "36"
		)
		(pin "37"
		)
		(pin "38"
		)
		(pin "39"
		)
		(pin "4"
		)
		(pin "40"
		)
		(pin "41"
		)
		(pin "42"
		)
		(pin "43"
		)
		(pin "44"
		)
		(pin "45"
		)
		(pin "46"
		)
		(pin "47"
		)
		(pin "48"
		)
		(pin "49"
		)
		(pin "5"
		)
		(pin "50"
		)
		(pin "51"
		)
		(pin "52"
		)
		(pin "53"
		)
		(pin "54"
		)
		(pin "55"
		)
		(pin "56"
		)
		(pin "57"
		)
		(pin "6"
		)
		(pin "7"
		)
		(pin "8"
		)
		(pin "9"
		)
		(instances
			(project "lpddr4-test-board"
				(path ""
					(reference "U4")
					(unit 1)
				)
			)
		)
	)
	(symbol
		(lib_id "antmicropower:GND")
		(at 363.22 189.23 0)
		(unit 1)
		(exclude_from_sim no)
		(in_bom yes)
		(on_board yes)
		(dnp no)
		(property "Reference" "#PWR0107"
			(at 372.11 191.77 0)
			(effects
				(font
					(size 1.27 1.27)
					(thickness 0.15)
				)
				(justify left bottom)
				(hide yes)
			)
		)
		(property "Value" "GND"
			(at 361.315 193.675 0)
			(effects
				(font
					(size 1.27 1.27)
					(thickness 0.15)
				)
				(justify left bottom)
			)
		)
		(property "Footprint" ""
			(at 372.11 196.85 0)
			(effects
				(font
					(size 1.27 1.27)
					(thickness 0.15)
				)
				(justify left bottom)
				(hide yes)
			)
		)
		(property "Datasheet" ""
			(at 372.11 201.93 0)
			(effects
				(font
					(size 1.27 1.27)
					(thickness 0.15)
				)
				(justify left bottom)
				(hide yes)
			)
		)
		(property "Description" ""
			(at 363.22 189.23 0)
			(effects
				(font
					(size 1.27 1.27)
				)
			)
		)
		(property "Author" "Antmicro"
			(at 372.11 196.85 0)
			(effects
				(font
					(size 1.27 1.27)
					(thickness 0.15)
				)
				(justify left bottom)
				(hide yes)
			)
		)
		(property "License" "Apache-2.0"
			(at 372.11 199.39 0)
			(effects
				(font
					(size 1.27 1.27)
					(thickness 0.15)
				)
				(justify left bottom)
				(hide yes)
			)
		)
		(pin "1"
		)
		(instances
			(project "lpddr4-test-board"
				(path ""
					(reference "#PWR0107")
					(unit 1)
				)
			)
		)
	)
	(symbol
		(lib_id "antmicropower:GND")
		(at 46.355 112.395 0)
		(unit 1)
		(exclude_from_sim no)
		(in_bom yes)
		(on_board yes)
		(dnp no)
		(property "Reference" "#PWR0111"
			(at 55.245 114.935 0)
			(effects
				(font
					(size 1.27 1.27)
					(thickness 0.15)
				)
				(justify left bottom)
				(hide yes)
			)
		)
		(property "Value" "GND"
			(at 44.45 116.84 0)
			(effects
				(font
					(size 1.27 1.27)
					(thickness 0.15)
				)
				(justify left bottom)
			)
		)
		(property "Footprint" ""
			(at 55.245 120.015 0)
			(effects
				(font
					(size 1.27 1.27)
					(thickness 0.15)
				)
				(justify left bottom)
				(hide yes)
			)
		)
		(property "Datasheet" ""
			(at 55.245 125.095 0)
			(effects
				(font
					(size 1.27 1.27)
					(thickness 0.15)
				)
				(justify left bottom)
				(hide yes)
			)
		)
		(property "Description" ""
			(at 46.355 112.395 0)
			(effects
				(font
					(size 1.27 1.27)
				)
			)
		)
		(property "Author" "Antmicro"
			(at 55.245 120.015 0)
			(effects
				(font
					(size 1.27 1.27)
					(thickness 0.15)
				)
				(justify left bottom)
				(hide yes)
			)
		)
		(property "License" "Apache-2.0"
			(at 55.245 122.555 0)
			(effects
				(font
					(size 1.27 1.27)
					(thickness 0.15)
				)
				(justify left bottom)
				(hide yes)
			)
		)
		(pin "1"
		)
		(instances
			(project "lpddr4-test-board"
				(path ""
					(reference "#PWR0111")
					(unit 1)
				)
			)
		)
	)
	(symbol
		(lib_id "antmicropower:GND")
		(at 370.84 185.42 0)
		(unit 1)
		(exclude_from_sim no)
		(in_bom yes)
		(on_board yes)
		(dnp no)
		(property "Reference" "#PWR0106"
			(at 379.73 187.96 0)
			(effects
				(font
					(size 1.27 1.27)
					(thickness 0.15)
				)
				(justify left bottom)
				(hide yes)
			)
		)
		(property "Value" "GND"
			(at 368.935 189.865 0)
			(effects
				(font
					(size 1.27 1.27)
					(thickness 0.15)
				)
				(justify left bottom)
			)
		)
		(property "Footprint" ""
			(at 379.73 193.04 0)
			(effects
				(font
					(size 1.27 1.27)
					(thickness 0.15)
				)
				(justify left bottom)
				(hide yes)
			)
		)
		(property "Datasheet" ""
			(at 379.73 198.12 0)
			(effects
				(font
					(size 1.27 1.27)
					(thickness 0.15)
				)
				(justify left bottom)
				(hide yes)
			)
		)
		(property "Description" ""
			(at 370.84 185.42 0)
			(effects
				(font
					(size 1.27 1.27)
				)
			)
		)
		(property "Author" "Antmicro"
			(at 379.73 193.04 0)
			(effects
				(font
					(size 1.27 1.27)
					(thickness 0.15)
				)
				(justify left bottom)
				(hide yes)
			)
		)
		(property "License" "Apache-2.0"
			(at 379.73 195.58 0)
			(effects
				(font
					(size 1.27 1.27)
					(thickness 0.15)
				)
				(justify left bottom)
				(hide yes)
			)
		)
		(pin "1"
		)
		(instances
			(project "lpddr4-test-board"
				(path ""
					(reference "#PWR0106")
					(unit 1)
				)
			)
		)
	)
	(symbol
		(lib_id "antmicropower:GND")
		(at 65.405 116.205 0)
		(unit 1)
		(exclude_from_sim no)
		(in_bom yes)
		(on_board yes)
		(dnp no)
		(property "Reference" "#PWR0116"
			(at 74.295 118.745 0)
			(effects
				(font
					(size 1.27 1.27)
					(thickness 0.15)
				)
				(justify left bottom)
				(hide yes)
			)
		)
		(property "Value" "GND"
			(at 63.5 120.65 0)
			(effects
				(font
					(size 1.27 1.27)
					(thickness 0.15)
				)
				(justify left bottom)
			)
		)
		(property "Footprint" ""
			(at 74.295 123.825 0)
			(effects
				(font
					(size 1.27 1.27)
					(thickness 0.15)
				)
				(justify left bottom)
				(hide yes)
			)
		)
		(property "Datasheet" ""
			(at 74.295 128.905 0)
			(effects
				(font
					(size 1.27 1.27)
					(thickness 0.15)
				)
				(justify left bottom)
				(hide yes)
			)
		)
		(property "Description" ""
			(at 65.405 116.205 0)
			(effects
				(font
					(size 1.27 1.27)
				)
			)
		)
		(property "Author" "Antmicro"
			(at 74.295 123.825 0)
			(effects
				(font
					(size 1.27 1.27)
					(thickness 0.15)
				)
				(justify left bottom)
				(hide yes)
			)
		)
		(property "License" "Apache-2.0"
			(at 74.295 126.365 0)
			(effects
				(font
					(size 1.27 1.27)
					(thickness 0.15)
				)
				(justify left bottom)
				(hide yes)
			)
		)
		(pin "1"
		)
		(instances
			(project "lpddr4-test-board"
				(path ""
					(reference "#PWR0116")
					(unit 1)
				)
			)
		)
	)
	(symbol
		(lib_id "antmicropower:GND")
		(at 195.58 262.89 0)
		(unit 1)
		(exclude_from_sim no)
		(in_bom yes)
		(on_board yes)
		(dnp no)
		(property "Reference" "#PWR033"
			(at 204.47 265.43 0)
			(effects
				(font
					(size 1.27 1.27)
					(thickness 0.15)
				)
				(justify left bottom)
				(hide yes)
			)
		)
		(property "Value" "GND"
			(at 193.675 267.335 0)
			(effects
				(font
					(size 1.27 1.27)
					(thickness 0.15)
				)
				(justify left bottom)
			)
		)
		(property "Footprint" ""
			(at 204.47 270.51 0)
			(effects
				(font
					(size 1.27 1.27)
					(thickness 0.15)
				)
				(justify left bottom)
				(hide yes)
			)
		)
		(property "Datasheet" ""
			(at 204.47 275.59 0)
			(effects
				(font
					(size 1.27 1.27)
					(thickness 0.15)
				)
				(justify left bottom)
				(hide yes)
			)
		)
		(property "Description" ""
			(at 195.58 262.89 0)
			(effects
				(font
					(size 1.27 1.27)
				)
			)
		)
		(property "Author" "Antmicro"
			(at 204.47 270.51 0)
			(effects
				(font
					(size 1.27 1.27)
					(thickness 0.15)
				)
				(justify left bottom)
				(hide yes)
			)
		)
		(property "License" "Apache-2.0"
			(at 204.47 273.05 0)
			(effects
				(font
					(size 1.27 1.27)
					(thickness 0.15)
				)
				(justify left bottom)
				(hide yes)
			)
		)
		(pin "1"
		)
		(instances
			(project "lpddr4-test-board"
				(path ""
					(reference "#PWR033")
					(unit 1)
				)
			)
		)
	)
	(symbol
		(lib_id "antmicropower:GND")
		(at 39.37 91.44 0)
		(unit 1)
		(exclude_from_sim no)
		(in_bom yes)
		(on_board yes)
		(dnp no)
		(property "Reference" "#PWR0114"
			(at 48.26 93.98 0)
			(effects
				(font
					(size 1.27 1.27)
					(thickness 0.15)
				)
				(justify left bottom)
				(hide yes)
			)
		)
		(property "Value" "GND"
			(at 37.465 95.885 0)
			(effects
				(font
					(size 1.27 1.27)
					(thickness 0.15)
				)
				(justify left bottom)
			)
		)
		(property "Footprint" ""
			(at 48.26 99.06 0)
			(effects
				(font
					(size 1.27 1.27)
					(thickness 0.15)
				)
				(justify left bottom)
				(hide yes)
			)
		)
		(property "Datasheet" ""
			(at 48.26 104.14 0)
			(effects
				(font
					(size 1.27 1.27)
					(thickness 0.15)
				)
				(justify left bottom)
				(hide yes)
			)
		)
		(property "Description" ""
			(at 39.37 91.44 0)
			(effects
				(font
					(size 1.27 1.27)
				)
			)
		)
		(property "Author" "Antmicro"
			(at 48.26 99.06 0)
			(effects
				(font
					(size 1.27 1.27)
					(thickness 0.15)
				)
				(justify left bottom)
				(hide yes)
			)
		)
		(property "License" "Apache-2.0"
			(at 48.26 101.6 0)
			(effects
				(font
					(size 1.27 1.27)
					(thickness 0.15)
				)
				(justify left bottom)
				(hide yes)
			)
		)
		(pin "1"
		)
		(instances
			(project "lpddr4-test-board"
				(path ""
					(reference "#PWR0114")
					(unit 1)
				)
			)
		)
	)
	(symbol
		(lib_id "antmicropower:GND")
		(at 209.55 160.02 0)
		(unit 1)
		(exclude_from_sim no)
		(in_bom yes)
		(on_board yes)
		(dnp no)
		(property "Reference" "#PWR0121"
			(at 218.44 162.56 0)
			(effects
				(font
					(size 1.27 1.27)
					(thickness 0.15)
				)
				(justify left bottom)
				(hide yes)
			)
		)
		(property "Value" "GND"
			(at 207.645 164.465 0)
			(effects
				(font
					(size 1.27 1.27)
					(thickness 0.15)
				)
				(justify left bottom)
			)
		)
		(property "Footprint" ""
			(at 218.44 167.64 0)
			(effects
				(font
					(size 1.27 1.27)
					(thickness 0.15)
				)
				(justify left bottom)
				(hide yes)
			)
		)
		(property "Datasheet" ""
			(at 218.44 172.72 0)
			(effects
				(font
					(size 1.27 1.27)
					(thickness 0.15)
				)
				(justify left bottom)
				(hide yes)
			)
		)
		(property "Description" ""
			(at 209.55 160.02 0)
			(effects
				(font
					(size 1.27 1.27)
				)
			)
		)
		(property "Author" "Antmicro"
			(at 218.44 167.64 0)
			(effects
				(font
					(size 1.27 1.27)
					(thickness 0.15)
				)
				(justify left bottom)
				(hide yes)
			)
		)
		(property "License" "Apache-2.0"
			(at 218.44 170.18 0)
			(effects
				(font
					(size 1.27 1.27)
					(thickness 0.15)
				)
				(justify left bottom)
				(hide yes)
			)
		)
		(pin "1"
		)
		(instances
			(project "lpddr4-test-board"
				(path ""
					(reference "#PWR0121")
					(unit 1)
				)
			)
		)
	)
	(symbol
		(lib_id "antmicropower:GND")
		(at 74.295 116.205 0)
		(unit 1)
		(exclude_from_sim no)
		(in_bom yes)
		(on_board yes)
		(dnp no)
		(property "Reference" "#PWR0119"
			(at 83.185 118.745 0)
			(effects
				(font
					(size 1.27 1.27)
					(thickness 0.15)
				)
				(justify left bottom)
				(hide yes)
			)
		)
		(property "Value" "GND"
			(at 72.39 120.65 0)
			(effects
				(font
					(size 1.27 1.27)
					(thickness 0.15)
				)
				(justify left bottom)
			)
		)
		(property "Footprint" ""
			(at 83.185 123.825 0)
			(effects
				(font
					(size 1.27 1.27)
					(thickness 0.15)
				)
				(justify left bottom)
				(hide yes)
			)
		)
		(property "Datasheet" ""
			(at 83.185 128.905 0)
			(effects
				(font
					(size 1.27 1.27)
					(thickness 0.15)
				)
				(justify left bottom)
				(hide yes)
			)
		)
		(property "Description" ""
			(at 74.295 116.205 0)
			(effects
				(font
					(size 1.27 1.27)
				)
			)
		)
		(property "Author" "Antmicro"
			(at 83.185 123.825 0)
			(effects
				(font
					(size 1.27 1.27)
					(thickness 0.15)
				)
				(justify left bottom)
				(hide yes)
			)
		)
		(property "License" "Apache-2.0"
			(at 83.185 126.365 0)
			(effects
				(font
					(size 1.27 1.27)
					(thickness 0.15)
				)
				(justify left bottom)
				(hide yes)
			)
		)
		(pin "1"
		)
		(instances
			(project "lpddr4-test-board"
				(path ""
					(reference "#PWR0119")
					(unit 1)
				)
			)
		)
	)
	(symbol
		(lib_id "antmicroTestPoints:TP_1mm_SMD")
		(at 131.445 57.785 0)
		(unit 1)
		(exclude_from_sim no)
		(in_bom yes)
		(on_board yes)
		(dnp no)
		(property "Reference" "TP1"
			(at 135.255 58.42 0)
			(effects
				(font
					(size 1.27 1.27)
					(thickness 0.15)
				)
				(justify left bottom)
			)
		)
		(property "Value" "TP_1mm_SMD"
			(at 146.685 65.405 0)
			(effects
				(font
					(size 1.27 1.27)
					(thickness 0.15)
				)
				(justify left bottom)
				(hide yes)
			)
		)
		(property "Footprint" "antmicro-footprints:TP_SMD_1mm"
			(at 146.685 67.945 0)
			(effects
				(font
					(size 1.27 1.27)
					(thickness 0.15)
				)
				(justify left bottom)
				(hide yes)
			)
		)
		(property "Datasheet" ""
			(at 146.685 70.485 0)
			(effects
				(font
					(size 1.27 1.27)
					(thickness 0.15)
				)
				(justify left bottom)
				(hide yes)
			)
		)
		(property "Description" ""
			(at 131.445 57.785 0)
			(effects
				(font
					(size 1.27 1.27)
				)
			)
		)
		(property "MPN" ""
			(at 131.445 57.785 0)
			(effects
				(font
					(size 1.27 1.27)
				)
				(justify left bottom)
				(hide yes)
			)
		)
		(property "Manufacturer" ""
			(at 131.445 57.785 0)
			(effects
				(font
					(size 1.27 1.27)
				)
				(justify left bottom)
				(hide yes)
			)
		)
		(property "Author" "Antmicro"
			(at 146.685 73.025 0)
			(effects
				(font
					(size 1.27 1.27)
					(thickness 0.15)
				)
				(justify left bottom)
				(hide yes)
			)
		)
		(property "License" "Apache-2.0"
			(at 146.685 75.565 0)
			(effects
				(font
					(size 1.27 1.27)
					(thickness 0.15)
				)
				(justify left bottom)
				(hide yes)
			)
		)
		(pin "1"
		)
		(instances
			(project "lpddr4-test-board"
				(path ""
					(reference "TP1")
					(unit 1)
				)
			)
		)
	)
	(symbol
		(lib_id "antmicropower:GND")
		(at 39.37 112.395 0)
		(unit 1)
		(exclude_from_sim no)
		(in_bom yes)
		(on_board yes)
		(dnp no)
		(property "Reference" "#PWR0110"
			(at 48.26 114.935 0)
			(effects
				(font
					(size 1.27 1.27)
					(thickness 0.15)
				)
				(justify left bottom)
				(hide yes)
			)
		)
		(property "Value" "GND"
			(at 37.465 116.84 0)
			(effects
				(font
					(size 1.27 1.27)
					(thickness 0.15)
				)
				(justify left bottom)
			)
		)
		(property "Footprint" ""
			(at 48.26 120.015 0)
			(effects
				(font
					(size 1.27 1.27)
					(thickness 0.15)
				)
				(justify left bottom)
				(hide yes)
			)
		)
		(property "Datasheet" ""
			(at 48.26 125.095 0)
			(effects
				(font
					(size 1.27 1.27)
					(thickness 0.15)
				)
				(justify left bottom)
				(hide yes)
			)
		)
		(property "Description" ""
			(at 39.37 112.395 0)
			(effects
				(font
					(size 1.27 1.27)
				)
			)
		)
		(property "Author" "Antmicro"
			(at 48.26 120.015 0)
			(effects
				(font
					(size 1.27 1.27)
					(thickness 0.15)
				)
				(justify left bottom)
				(hide yes)
			)
		)
		(property "License" "Apache-2.0"
			(at 48.26 122.555 0)
			(effects
				(font
					(size 1.27 1.27)
					(thickness 0.15)
				)
				(justify left bottom)
				(hide yes)
			)
		)
		(pin "1"
		)
		(instances
			(project "lpddr4-test-board"
				(path ""
					(reference "#PWR0110")
					(unit 1)
				)
			)
		)
	)
	(symbol
		(lib_id "antmicropower:GND")
		(at 259.08 243.205 0)
		(unit 1)
		(exclude_from_sim no)
		(in_bom yes)
		(on_board yes)
		(dnp no)
		(property "Reference" "#PWR040"
			(at 267.97 245.745 0)
			(effects
				(font
					(size 1.27 1.27)
					(thickness 0.15)
				)
				(justify left bottom)
				(hide yes)
			)
		)
		(property "Value" "GND"
			(at 257.175 247.65 0)
			(effects
				(font
					(size 1.27 1.27)
					(thickness 0.15)
				)
				(justify left bottom)
			)
		)
		(property "Footprint" ""
			(at 267.97 250.825 0)
			(effects
				(font
					(size 1.27 1.27)
					(thickness 0.15)
				)
				(justify left bottom)
				(hide yes)
			)
		)
		(property "Datasheet" ""
			(at 267.97 255.905 0)
			(effects
				(font
					(size 1.27 1.27)
					(thickness 0.15)
				)
				(justify left bottom)
				(hide yes)
			)
		)
		(property "Description" ""
			(at 259.08 243.205 0)
			(effects
				(font
					(size 1.27 1.27)
				)
			)
		)
		(property "Author" "Antmicro"
			(at 267.97 250.825 0)
			(effects
				(font
					(size 1.27 1.27)
					(thickness 0.15)
				)
				(justify left bottom)
				(hide yes)
			)
		)
		(property "License" "Apache-2.0"
			(at 267.97 253.365 0)
			(effects
				(font
					(size 1.27 1.27)
					(thickness 0.15)
				)
				(justify left bottom)
				(hide yes)
			)
		)
		(pin "1"
		)
		(instances
			(project "lpddr4-test-board"
				(path ""
					(reference "#PWR040")
					(unit 1)
				)
			)
		)
	)
	(symbol
		(lib_id "antmicropower:GND")
		(at 259.08 223.52 0)
		(unit 1)
		(exclude_from_sim no)
		(in_bom yes)
		(on_board yes)
		(dnp no)
		(property "Reference" "#PWR039"
			(at 267.97 226.06 0)
			(effects
				(font
					(size 1.27 1.27)
					(thickness 0.15)
				)
				(justify left bottom)
				(hide yes)
			)
		)
		(property "Value" "GND"
			(at 257.175 227.965 0)
			(effects
				(font
					(size 1.27 1.27)
					(thickness 0.15)
				)
				(justify left bottom)
			)
		)
		(property "Footprint" ""
			(at 267.97 231.14 0)
			(effects
				(font
					(size 1.27 1.27)
					(thickness 0.15)
				)
				(justify left bottom)
				(hide yes)
			)
		)
		(property "Datasheet" ""
			(at 267.97 236.22 0)
			(effects
				(font
					(size 1.27 1.27)
					(thickness 0.15)
				)
				(justify left bottom)
				(hide yes)
			)
		)
		(property "Description" ""
			(at 259.08 223.52 0)
			(effects
				(font
					(size 1.27 1.27)
				)
			)
		)
		(property "Author" "Antmicro"
			(at 267.97 231.14 0)
			(effects
				(font
					(size 1.27 1.27)
					(thickness 0.15)
				)
				(justify left bottom)
				(hide yes)
			)
		)
		(property "License" "Apache-2.0"
			(at 267.97 233.68 0)
			(effects
				(font
					(size 1.27 1.27)
					(thickness 0.15)
				)
				(justify left bottom)
				(hide yes)
			)
		)
		(pin "1"
		)
		(instances
			(project "lpddr4-test-board"
				(path ""
					(reference "#PWR039")
					(unit 1)
				)
			)
		)
	)
	(symbol
		(lib_id "antmicropower:GND")
		(at 379.73 95.25 0)
		(unit 1)
		(exclude_from_sim no)
		(in_bom yes)
		(on_board yes)
		(dnp no)
		(property "Reference" "#PWR0105"
			(at 388.62 97.79 0)
			(effects
				(font
					(size 1.27 1.27)
					(thickness 0.15)
				)
				(justify left bottom)
				(hide yes)
			)
		)
		(property "Value" "GND"
			(at 377.825 99.695 0)
			(effects
				(font
					(size 1.27 1.27)
					(thickness 0.15)
				)
				(justify left bottom)
			)
		)
		(property "Footprint" ""
			(at 388.62 102.87 0)
			(effects
				(font
					(size 1.27 1.27)
					(thickness 0.15)
				)
				(justify left bottom)
				(hide yes)
			)
		)
		(property "Datasheet" ""
			(at 388.62 107.95 0)
			(effects
				(font
					(size 1.27 1.27)
					(thickness 0.15)
				)
				(justify left bottom)
				(hide yes)
			)
		)
		(property "Description" ""
			(at 379.73 95.25 0)
			(effects
				(font
					(size 1.27 1.27)
				)
			)
		)
		(property "Author" "Antmicro"
			(at 388.62 102.87 0)
			(effects
				(font
					(size 1.27 1.27)
					(thickness 0.15)
				)
				(justify left bottom)
				(hide yes)
			)
		)
		(property "License" "Apache-2.0"
			(at 388.62 105.41 0)
			(effects
				(font
					(size 1.27 1.27)
					(thickness 0.15)
				)
				(justify left bottom)
				(hide yes)
			)
		)
		(pin "1"
		)
		(instances
			(project "lpddr4-test-board"
				(path ""
					(reference "#PWR0105")
					(unit 1)
				)
			)
		)
	)
	(symbol
		(lib_id "antmicroUSBConnectors:USB-Micro-B_WE_629105150521")
		(at 212.09 125.73 0)
		(mirror y)
		(unit 1)
		(exclude_from_sim no)
		(in_bom yes)
		(on_board yes)
		(dnp no)
		(property "Reference" "J1"
			(at 224.79 119.38 0)
			(effects
				(font
					(size 1.27 1.27)
					(thickness 0.15)
				)
				(justify left)
			)
		)
		(property "Value" "USB-Micro-B_629105150521"
			(at 238.76 121.92 0)
			(effects
				(font
					(size 1.27 1.27)
					(thickness 0.15)
				)
				(justify left)
			)
		)
		(property "Footprint" "antmicro-footprints:USB-Micro-B_Receptacle_WE_629105150521"
			(at 187.96 128.27 0)
			(effects
				(font
					(size 1.27 1.27)
					(thickness 0.15)
				)
				(justify left bottom)
				(hide yes)
			)
		)
		(property "Datasheet" "https://www.we-online.com/components/products/datasheet/629105150521.pdf"
			(at 187.96 130.81 0)
			(effects
				(font
					(size 1.27 1.27)
					(thickness 0.15)
				)
				(justify left bottom)
				(hide yes)
			)
		)
		(property "Description" ""
			(at 212.09 125.73 0)
			(effects
				(font
					(size 1.27 1.27)
				)
			)
		)
		(property "MPN" "629105150521"
			(at 187.96 133.35 0)
			(effects
				(font
					(size 1.27 1.27)
					(thickness 0.15)
				)
				(justify left bottom)
				(hide yes)
			)
		)
		(property "Manufacturer" "Würth Elektronik"
			(at 187.96 135.89 0)
			(effects
				(font
					(size 1.27 1.27)
					(thickness 0.15)
				)
				(justify left bottom)
				(hide yes)
			)
		)
		(property "Author" "Antmicro"
			(at 187.96 138.43 0)
			(effects
				(font
					(size 1.27 1.27)
					(thickness 0.15)
				)
				(justify left bottom)
				(hide yes)
			)
		)
		(property "License" "Apache-2.0"
			(at 187.96 140.97 0)
			(effects
				(font
					(size 1.27 1.27)
					(thickness 0.15)
				)
				(justify left bottom)
				(hide yes)
			)
		)
		(pin "1"
		)
		(pin "2"
		)
		(pin "3"
		)
		(pin "4"
		)
		(pin "5"
		)
		(pin "SH"
		)
		(instances
			(project "lpddr4-test-board"
				(path ""
					(reference "J1")
					(unit 1)
				)
			)
		)
	)
	(symbol
		(lib_id "antmicropower:GND")
		(at 196.215 243.205 0)
		(unit 1)
		(exclude_from_sim no)
		(in_bom yes)
		(on_board yes)
		(dnp no)
		(property "Reference" "#PWR034"
			(at 205.105 245.745 0)
			(effects
				(font
					(size 1.27 1.27)
					(thickness 0.15)
				)
				(justify left bottom)
				(hide yes)
			)
		)
		(property "Value" "GND"
			(at 194.31 247.65 0)
			(effects
				(font
					(size 1.27 1.27)
					(thickness 0.15)
				)
				(justify left bottom)
			)
		)
		(property "Footprint" ""
			(at 205.105 250.825 0)
			(effects
				(font
					(size 1.27 1.27)
					(thickness 0.15)
				)
				(justify left bottom)
				(hide yes)
			)
		)
		(property "Datasheet" ""
			(at 205.105 255.905 0)
			(effects
				(font
					(size 1.27 1.27)
					(thickness 0.15)
				)
				(justify left bottom)
				(hide yes)
			)
		)
		(property "Description" ""
			(at 196.215 243.205 0)
			(effects
				(font
					(size 1.27 1.27)
				)
			)
		)
		(property "Author" "Antmicro"
			(at 205.105 250.825 0)
			(effects
				(font
					(size 1.27 1.27)
					(thickness 0.15)
				)
				(justify left bottom)
				(hide yes)
			)
		)
		(property "License" "Apache-2.0"
			(at 205.105 253.365 0)
			(effects
				(font
					(size 1.27 1.27)
					(thickness 0.15)
				)
				(justify left bottom)
				(hide yes)
			)
		)
		(pin "1"
		)
		(instances
			(project "lpddr4-test-board"
				(path ""
					(reference "#PWR034")
					(unit 1)
				)
			)
		)
	)
	(symbol
		(lib_id "antmicropower:GND")
		(at 279.4 88.9 0)
		(unit 1)
		(exclude_from_sim no)
		(in_bom yes)
		(on_board yes)
		(dnp no)
		(property "Reference" "#PWR0103"
			(at 288.29 91.44 0)
			(effects
				(font
					(size 1.27 1.27)
					(thickness 0.15)
				)
				(justify left bottom)
				(hide yes)
			)
		)
		(property "Value" "GND"
			(at 277.495 93.345 0)
			(effects
				(font
					(size 1.27 1.27)
					(thickness 0.15)
				)
				(justify left bottom)
			)
		)
		(property "Footprint" ""
			(at 288.29 96.52 0)
			(effects
				(font
					(size 1.27 1.27)
					(thickness 0.15)
				)
				(justify left bottom)
				(hide yes)
			)
		)
		(property "Datasheet" ""
			(at 288.29 101.6 0)
			(effects
				(font
					(size 1.27 1.27)
					(thickness 0.15)
				)
				(justify left bottom)
				(hide yes)
			)
		)
		(property "Description" ""
			(at 279.4 88.9 0)
			(effects
				(font
					(size 1.27 1.27)
				)
			)
		)
		(property "Author" "Antmicro"
			(at 288.29 96.52 0)
			(effects
				(font
					(size 1.27 1.27)
					(thickness 0.15)
				)
				(justify left bottom)
				(hide yes)
			)
		)
		(property "License" "Apache-2.0"
			(at 288.29 99.06 0)
			(effects
				(font
					(size 1.27 1.27)
					(thickness 0.15)
				)
				(justify left bottom)
				(hide yes)
			)
		)
		(pin "1"
		)
		(instances
			(project "lpddr4-test-board"
				(path ""
					(reference "#PWR0103")
					(unit 1)
				)
			)
		)
	)
)
